G04 ================== begin FILE IDENTIFICATION RECORD ==================*
G04 Layout Name:  D:/<user>/Wistron_project/16316-1/gbr-0621/16316-1.brd*
G04 Film Name:    DP_REF_L6*
G04 File Format:  Gerber RS274X*
G04 File Origin:  Cadence Allegro 16.5-S056*
G04 Origin Date:  Wed Jun 21 09:32:33 2017*
G04 *
G04 Layer:  BOARD GEOMETRY/DP_REF_L6_TBL*
G04 Layer:  BOARD GEOMETRY/DP_REF_L6_L6*
G04 Layer:  BOARD GEOMETRY/PANEL_OUTLINE*
G04 *
G04 Offset:    (0.00 0.00)*
G04 Mirror:    No*
G04 Mode:      Positive*
G04 Rotation:  0*
G04 FullContactRelief:  No*
G04 UndefLineWidth:     6.00*
G04 ================== end FILE IDENTIFICATION RECORD ====================*
%FSLAX35Y35*MOIN*%
%IR0*IPPOS*OFA0.00000B0.00000*MIA0B0*SFA1.00000B1.00000*%
%ADD10C,.02*%
%ADD11C,.004*%
%ADD12C,.006*%
%ADD13C,.0055*%
G75*
%LPD*%
G75*
G54D10*
G01X877071Y397916D02*
X1682071D01*
G01X877071Y363266D02*
X1682071D01*
G01X877071Y536516D02*
Y363266D01*
G01Y467216D02*
X1682071D01*
G01X877071Y432566D02*
X1682071D01*
G01X877071Y536516D02*
X1682071D01*
G01X877071Y501866D02*
X1682071D01*
G01X1052071Y536516D02*
Y363266D01*
G01X1367071Y536516D02*
Y363266D01*
G01X1472071Y536516D02*
Y363266D01*
G01X1682071Y536516D02*
Y363266D01*
G54D11*
G01X357761Y40739D02*
X359137D01*
G01X357761Y41939D02*
X359137D01*
G01X355699Y42801D02*
G03X357761Y40739I2062J0D01*
G01X356899Y42801D02*
G03X357761Y41939I862J0D01*
G01X355699Y50972D02*
Y42801D01*
G01X356899Y50616D02*
Y42801D01*
G01X374405Y79775D02*
X355699Y50972D01*
G01X393924Y107626D02*
X356899Y50616D01*
G01X393924Y107626D02*
X356899Y50616D01*
G01X357761Y41939D02*
X359137D01*
G01X357761Y40739D02*
X359137D01*
G01X356899Y42801D02*
G03X357761Y41939I862J0D01*
G01X355699Y42801D02*
G03X357761Y40739I2062J0D01*
G01X356899Y50616D02*
Y42801D01*
G01X355699Y50972D02*
Y42801D01*
G01X393924Y107626D02*
X356899Y50616D01*
G01X374405Y79775D02*
X355699Y50972D01*
G01X350674Y45463D02*
X352050D01*
G01X350674Y46663D02*
X352050D01*
G01X348613Y47524D02*
G03X350674Y45463I2061J0D01*
G01X349813Y47524D02*
G03X350674Y46663I861J0D01*
G01X348613Y52447D02*
Y47524D01*
G01X349813Y52320D02*
Y47524D01*
G01X350674Y46663D02*
X352050D01*
G01X350674Y45463D02*
X352050D01*
G01X349813Y47524D02*
G03X350674Y46663I861J0D01*
G01X348613Y47524D02*
G03X350674Y45463I2061J0D01*
G01X349813Y52320D02*
Y47524D01*
G01X348613Y52447D02*
Y47524D01*
G01X343588Y40739D02*
X344964D01*
G01X343588Y41939D02*
X344964D01*
G01X341526Y42801D02*
G03X343588Y40739I2062J0D01*
G01X342726Y42801D02*
G03X343588Y41939I862J0D01*
G01X341526Y50369D02*
Y42801D01*
G01X342726Y50242D02*
Y42801D01*
G01X341856Y51924D02*
X341526Y50369D01*
G01X342984Y51457D02*
X342726Y50242D01*
G01X343588Y41939D02*
X344964D01*
G01X343588Y40739D02*
X344964D01*
G01X342726Y42801D02*
G03X343588Y41939I862J0D01*
G01X341526Y42801D02*
G03X343588Y40739I2062J0D01*
G01X342726Y50242D02*
Y42801D01*
G01X341526Y50369D02*
Y42801D01*
G01X342984Y51457D02*
X342726Y50242D01*
G01X341856Y51924D02*
X341526Y50369D01*
G01X335500Y51136D02*
X336221Y54528D01*
G01X334300Y47664D02*
Y51263D01*
G01X335500Y47664D02*
Y51136D01*
G01X336501Y45463D02*
G02X334300Y47664I0J2201D01*
G01X336501Y46663D02*
G02X335500Y47664I0J1001D01*
G01X337877Y45463D02*
X336501D01*
G01X337877Y46663D02*
X336501D01*
G01X335500Y51136D02*
X336221Y54528D01*
G01X335500Y47664D02*
Y51136D01*
G01X334300Y47664D02*
Y51263D01*
G01X336501Y46663D02*
G02X335500Y47664I0J1001D01*
G01X336501Y45463D02*
G02X334300Y47664I0J2201D01*
G01X337877Y46663D02*
X336501D01*
G01X337877Y45463D02*
X336501D01*
G01X386107Y40739D02*
X387483D01*
G01X386107Y41939D02*
X387483D01*
G01X384046Y42800D02*
G03X386107Y40739I2061J0D01*
G01X385246Y42800D02*
G03X386107Y41939I861J0D01*
G01X384046Y50544D02*
Y42800D01*
G01X385246Y50417D02*
Y42800D01*
G01X386135Y60377D02*
X384046Y50544D01*
G01X387263Y59910D02*
X385246Y50417D01*
G01X386107Y41939D02*
X387483D01*
G01X386107Y40739D02*
X387483D01*
G01X385246Y42800D02*
G03X386107Y41939I861J0D01*
G01X384046Y42800D02*
G03X386107Y40739I2061J0D01*
G01X385246Y50417D02*
Y42800D01*
G01X384046Y50544D02*
Y42800D01*
G01X387263Y59910D02*
X385246Y50417D01*
G01X386135Y60377D02*
X384046Y50544D01*
G01X379021Y45463D02*
X380397D01*
G01X379021Y46663D02*
X380397D01*
G01X376960Y47524D02*
G03X379021Y45463I2061J0D01*
G01X378160Y47524D02*
G03X379021Y46663I861J0D01*
G01X376960Y52286D02*
Y47524D01*
G01X378160Y52159D02*
Y47524D01*
G01X379021Y46663D02*
X380397D01*
G01X379021Y45463D02*
X380397D01*
G01X378160Y47524D02*
G03X379021Y46663I861J0D01*
G01X376960Y47524D02*
G03X379021Y45463I2061J0D01*
G01X378160Y52159D02*
Y47524D01*
G01X376960Y52286D02*
Y47524D01*
G01X371934Y40739D02*
X373310D01*
G01X371934Y41939D02*
X373310D01*
G01X369872Y42801D02*
G03X371934Y40739I2062J0D01*
G01X371072Y42801D02*
G03X371934Y41939I862J0D01*
G01X369872Y52026D02*
Y42801D01*
G01X371072Y51899D02*
Y42801D01*
G01X371934Y41939D02*
X373310D01*
G01X371934Y40739D02*
X373310D01*
G01X371072Y42801D02*
G03X371934Y41939I862J0D01*
G01X369872Y42801D02*
G03X371934Y40739I2062J0D01*
G01X371072Y51899D02*
Y42801D01*
G01X369872Y52026D02*
Y42801D01*
G01X364847Y45463D02*
X366223D01*
G01X364847Y46663D02*
X366223D01*
G01X362786Y47524D02*
G03X364847Y45463I2061J0D01*
G01X363986Y47524D02*
G03X364847Y46663I861J0D01*
G01X362786Y52649D02*
Y47524D01*
G01X363986Y52522D02*
Y47524D01*
G01X364847Y46663D02*
X366223D01*
G01X364847Y45463D02*
X366223D01*
G01X363986Y47524D02*
G03X364847Y46663I861J0D01*
G01X362786Y47524D02*
G03X364847Y45463I2061J0D01*
G01X363986Y52522D02*
Y47524D01*
G01X362786Y52649D02*
Y47524D01*
G01X392796Y108093D02*
X374405Y79775D01*
G01X392796Y108093D02*
X374405Y79775D01*
G01X348888Y53741D02*
X348613Y52447D01*
G01X350016Y53274D02*
X349813Y52320D01*
G01X351042Y57057D02*
X348888Y53741D01*
G01X351910Y56189D02*
X350016Y53274D01*
G01X354819Y59511D02*
X351042Y57057D01*
G01X355472Y58504D02*
X351910Y56189D01*
G01X355687Y58643D02*
X355472Y58503D01*
G01X389541Y112976D02*
X354819Y59511D01*
G01X390669Y112509D02*
X355687Y58643D01*
G01X350016Y53274D02*
X349813Y52320D01*
G01X348888Y53741D02*
X348613Y52447D01*
G01X351910Y56189D02*
X350016Y53274D01*
G01X351042Y57057D02*
X348888Y53741D01*
G01X355472Y58504D02*
X351910Y56189D01*
G01X354819Y59511D02*
X351042Y57057D01*
G01X355687Y58643D02*
X355472Y58503D01*
G01X354819Y59511D02*
X351042Y57057D01*
G01X390669Y112509D02*
X355687Y58643D01*
G01X389541Y112976D02*
X354819Y59511D01*
G01X346610Y59243D02*
X341856Y51924D01*
G01X347478Y58375D02*
X342984Y51457D01*
G01X351837Y62637D02*
X346610Y59243D01*
G01X352705Y61769D02*
X347478Y58375D01*
G01X386155Y115481D02*
X351837Y62637D01*
G01X387283Y115014D02*
X352705Y61769D01*
G01X347478Y58375D02*
X342984Y51457D01*
G01X346610Y59243D02*
X341856Y51924D01*
G01X352705Y61769D02*
X347478Y58375D01*
G01X351837Y62637D02*
X346610Y59243D01*
G01X387283Y115014D02*
X352705Y61769D01*
G01X386155Y115481D02*
X351837Y62637D01*
G01X349354Y66545D02*
X382805Y118055D01*
G01X350222Y65677D02*
X383933Y117588D01*
G01X337664Y58954D02*
X349354Y66545D01*
G01X338532Y58086D02*
X350222Y65677D01*
G01X335093Y54995D02*
X337664Y58954D01*
G01X336221Y54528D02*
X338532Y58086D01*
G01X334300Y51263D02*
X335093Y54995D01*
G01X350222Y65677D02*
X383933Y117588D01*
G01X349354Y66545D02*
X382805Y118055D01*
G01X338532Y58086D02*
X350222Y65677D01*
G01X337664Y58954D02*
X349354Y66545D01*
G01X336221Y54528D02*
X338532Y58086D01*
G01X335093Y54995D02*
X337664Y58954D01*
G01X334300Y51263D02*
X335093Y54995D01*
G01X407839Y93796D02*
X386135Y60377D01*
G01X407839Y93796D02*
X386135Y60377D01*
G01X378597Y59993D02*
X376960Y52286D01*
G01X379725Y59526D02*
X378160Y52159D01*
G01X404167Y99365D02*
X378597Y59993D01*
G01X405295Y98898D02*
X379725Y59526D01*
G01D02*
X378160Y52159D01*
G01X378597Y59993D02*
X376960Y52286D01*
G01X405295Y98898D02*
X379725Y59526D01*
G01X404167Y99365D02*
X378597Y59993D01*
G01X371390Y59169D02*
X369872Y52026D01*
G01X372518Y58702D02*
X371072Y51899D01*
G01X400517Y104019D02*
X371390Y59169D01*
G01X401645Y103552D02*
X372518Y58702D01*
G01D02*
X371072Y51899D01*
G01X371390Y59169D02*
X369872Y52026D01*
G01X401645Y103552D02*
X372518Y58702D01*
G01X400517Y104019D02*
X371390Y59169D01*
G01X363398Y55530D02*
X362786Y52649D01*
G01X364526Y55063D02*
X363986Y52522D01*
G01X396873Y107071D02*
X363398Y55530D01*
G01X398001Y106604D02*
X364526Y55063D01*
G01D02*
X363986Y52522D01*
G01X363398Y55530D02*
X362786Y52649D01*
G01X398001Y106604D02*
X364526Y55063D01*
G01X396873Y107071D02*
X363398Y55530D01*
G01X393339Y149279D02*
X386155Y115481D01*
G01X385076Y168940D02*
X387367Y167335D01*
G01X385939Y169802D02*
X388247Y168185D01*
G01X384154Y170259D02*
X385076Y168940D01*
G01X385290Y170730D02*
X385939Y169802D01*
G01X383996Y171155D02*
X384154Y170259D01*
G01X385196Y171261D02*
X385290Y170730D01*
G01X383996Y177209D02*
Y171155D01*
G01X385196Y177103D02*
Y171261D01*
G01X393339Y149279D02*
X386155Y115481D01*
G01X385939Y169802D02*
X388247Y168185D01*
G01X385076Y168940D02*
X387367Y167335D01*
G01X385290Y170730D02*
X385939Y169802D01*
G01X384154Y170259D02*
X385076Y168940D01*
G01X385196Y171261D02*
X385290Y170730D01*
G01X383996Y171155D02*
X384154Y170259D01*
G01X385196Y177103D02*
Y171261D01*
G01X383996Y177209D02*
Y171155D01*
G01X377996Y171156D02*
Y177209D01*
G01X379196Y171261D02*
Y177103D01*
G01X378201Y169990D02*
X377996Y171156D01*
G01X379337Y170461D02*
X379196Y171261D01*
G01X378808Y169123D02*
X378201Y169990D01*
G01X379670Y169986D02*
X379337Y170461D01*
G01X385709Y164293D02*
X378808Y169123D01*
G01X386592Y165140D02*
X379670Y169986D01*
G01X385711Y164293D02*
X385709D01*
G01X386592Y165140D02*
X379670Y169986D01*
G01X387657Y161297D02*
X385711Y164293D01*
G01X388785Y161765D02*
X386593Y165140D01*
G01X382805Y118055D02*
X389829Y151095D01*
G01X383933Y117588D02*
X391056Y151095D01*
G01X379196Y171261D02*
Y177103D01*
G01X377996Y171156D02*
Y177209D01*
G01X379337Y170461D02*
X379196Y171261D01*
G01X378201Y169990D02*
X377996Y171156D01*
G01X379670Y169986D02*
X379337Y170461D01*
G01X378808Y169123D02*
X378201Y169990D01*
G01X386592Y165140D02*
X379670Y169986D01*
G01X385709Y164293D02*
X378808Y169123D01*
G01X385711Y164293D02*
X385709D01*
G01X388785Y161765D02*
X386593Y165140D01*
G01X387657Y161297D02*
X385711Y164293D01*
G01X383933Y117588D02*
X391056Y151095D01*
G01X382805Y118055D02*
X389829Y151095D01*
G01X384269Y178758D02*
X383996Y177209D01*
G01X385405Y178288D02*
X385196Y177103D01*
G01X385230Y180132D02*
X384269Y178758D01*
G01X386193Y179413D02*
X385405Y178288D01*
G01X385590Y180584D02*
X385230Y180132D01*
G01X386421Y179701D02*
X386193Y179413D01*
G01X388195Y182409D02*
X385590Y180584D01*
G01X389077Y181560D02*
X386421Y179701D01*
G01X385405Y178288D02*
X385196Y177103D01*
G01X384269Y178758D02*
X383996Y177209D01*
G01X386193Y179413D02*
X385405Y178288D01*
G01X385230Y180132D02*
X384269Y178758D01*
G01X386421Y179701D02*
X386193Y179413D01*
G01X385590Y180584D02*
X385230Y180132D01*
G01X389077Y181560D02*
X386421Y179701D01*
G01X388195Y182409D02*
X385590Y180584D01*
G01X385383Y189782D02*
X393279Y194907D01*
G01X386291Y188940D02*
X389970Y191328D01*
G01X380714Y181251D02*
X385383Y189782D01*
G01X381634Y180430D02*
X386291Y188940D01*
G01X379339Y180288D02*
X380714Y181251D01*
G01X380202Y179426D02*
X381634Y180430D01*
G01X378269Y178758D02*
X379339Y180288D01*
G01X379405Y178288D02*
X380202Y179426D01*
G01X377996Y177209D02*
X378269Y178758D01*
G01X379196Y177103D02*
X379405Y178288D01*
G01X385383Y189782D02*
X393279Y194907D01*
G01X386291Y188940D02*
X389970Y191328D01*
G01X385383Y189782D02*
X393279Y194907D01*
G01X381634Y180430D02*
X386291Y188940D01*
G01X380714Y181251D02*
X385383Y189782D01*
G01X380202Y179426D02*
X381634Y180430D01*
G01X379339Y180288D02*
X380714Y181251D01*
G01X379405Y178288D02*
X380202Y179426D01*
G01X378269Y178758D02*
X379339Y180288D01*
G01X379196Y177103D02*
X379405Y178288D01*
G01X377996Y177209D02*
X378269Y178758D01*
G01X447826Y47524D02*
G03X449887Y45463I2061J0D01*
G01X447826Y72702D02*
Y47524D01*
G01D02*
G03X449887Y45463I2061J0D01*
G01X447826Y72702D02*
Y47524D01*
G01X442800Y40739D02*
X444176D01*
G01X442800Y41939D02*
X444176D01*
G01X440739Y42800D02*
G03X442800Y40739I2061J0D01*
G01X441939Y42800D02*
G03X442800Y41939I861J0D01*
G01X440739Y61312D02*
Y42800D01*
G01X441939Y61186D02*
Y42800D01*
G01X442800Y41939D02*
X444176D01*
G01X442800Y40739D02*
X444176D01*
G01X441939Y42800D02*
G03X442800Y41939I861J0D01*
G01X440739Y42800D02*
G03X442800Y40739I2061J0D01*
G01X441939Y61186D02*
Y42800D01*
G01X440739Y61312D02*
Y42800D01*
G01X435714Y45463D02*
X437090D01*
G01X435714Y46663D02*
X437090D01*
G01X433653Y47524D02*
G03X435714Y45463I2061J0D01*
G01X434853Y47524D02*
G03X435714Y46663I861J0D01*
G01X433653Y57211D02*
Y47524D01*
G01X434853Y57084D02*
Y47524D01*
G01X435714Y46663D02*
X437090D01*
G01X435714Y45463D02*
X437090D01*
G01X434853Y47524D02*
G03X435714Y46663I861J0D01*
G01X433653Y47524D02*
G03X435714Y45463I2061J0D01*
G01X434853Y57084D02*
Y47524D01*
G01X433653Y57211D02*
Y47524D01*
G01X428627Y40739D02*
X430003D01*
G01X428627Y41939D02*
X430003D01*
G01X426565Y42801D02*
G03X428627Y40739I2062J0D01*
G01X427765Y42801D02*
G03X428627Y41939I862J0D01*
G01X426565Y51968D02*
Y42801D01*
G01X427765Y51841D02*
Y42801D01*
G01X428627Y41939D02*
X430003D01*
G01X428627Y40739D02*
X430003D01*
G01X427765Y42801D02*
G03X428627Y41939I862J0D01*
G01X426565Y42801D02*
G03X428627Y40739I2062J0D01*
G01X427765Y51841D02*
Y42801D01*
G01X426565Y51968D02*
Y42801D01*
G01X421540Y45463D02*
X422916D01*
G01X421540Y46663D02*
X422916D01*
G01X419479Y47524D02*
G03X421540Y45463I2061J0D01*
G01X420679Y47524D02*
G03X421540Y46663I861J0D01*
G01X419479Y56873D02*
Y47524D01*
G01X420679Y56746D02*
Y47524D01*
G01X421540Y46663D02*
X422916D01*
G01X421540Y45463D02*
X422916D01*
G01X420679Y47524D02*
G03X421540Y46663I861J0D01*
G01X419479Y47524D02*
G03X421540Y45463I2061J0D01*
G01X420679Y56746D02*
Y47524D01*
G01X419479Y56873D02*
Y47524D01*
G01X414454Y40739D02*
X415830D01*
G01X414454Y41939D02*
X415830D01*
G01X412392Y42801D02*
G03X414454Y40739I2062J0D01*
G01X413592Y42801D02*
G03X414454Y41939I862J0D01*
G01X412392Y52441D02*
Y42801D01*
G01X413592Y52314D02*
Y42801D01*
G01X414454Y41939D02*
X415830D01*
G01X414454Y40739D02*
X415830D01*
G01X413592Y42801D02*
G03X414454Y41939I862J0D01*
G01X412392Y42801D02*
G03X414454Y40739I2062J0D01*
G01X413592Y52314D02*
Y42801D01*
G01X412392Y52441D02*
Y42801D01*
G01X407367Y45463D02*
X408743D01*
G01X407367Y46663D02*
X408743D01*
G01X405306Y47524D02*
G03X407367Y45463I2061J0D01*
G01X406506Y47524D02*
G03X407367Y46663I861J0D01*
G01X405306Y52879D02*
Y47524D01*
G01X406506Y52752D02*
Y47524D01*
G01X407367Y46663D02*
X408743D01*
G01X407367Y45463D02*
X408743D01*
G01X406506Y47524D02*
G03X407367Y46663I861J0D01*
G01X405306Y47524D02*
G03X407367Y45463I2061J0D01*
G01X406506Y52752D02*
Y47524D01*
G01X405306Y52879D02*
Y47524D01*
G01X400281Y40739D02*
X401657D01*
G01X400281Y41939D02*
X401657D01*
G01X398219Y42801D02*
G03X400281Y40739I2062J0D01*
G01X399419Y42801D02*
G03X400281Y41939I862J0D01*
G01X398219Y52435D02*
Y42801D01*
G01X399419Y52308D02*
Y42801D01*
G01X400281Y41939D02*
X401657D01*
G01X400281Y40739D02*
X401657D01*
G01X399419Y42801D02*
G03X400281Y41939I862J0D01*
G01X398219Y42801D02*
G03X400281Y40739I2062J0D01*
G01X399419Y52308D02*
Y42801D01*
G01X398219Y52435D02*
Y42801D01*
G01X393194Y45463D02*
X394570D01*
G01X393194Y46663D02*
X394570D01*
G01X391133Y47524D02*
G03X393194Y45463I2061J0D01*
G01X392333Y47524D02*
G03X393194Y46663I861J0D01*
G01X391133Y51326D02*
Y47524D01*
G01X392333Y51199D02*
Y47524D01*
G01X394027Y59167D02*
X392333Y51199D01*
G01X393194Y46663D02*
X394570D01*
G01X393194Y45463D02*
X394570D01*
G01X392333Y47524D02*
G03X393194Y46663I861J0D01*
G01X391133Y47524D02*
G03X393194Y45463I2061J0D01*
G01X392333Y51199D02*
Y47524D01*
G01X391133Y51326D02*
Y47524D01*
G01X394027Y59167D02*
X392333Y51199D01*
G01X466438Y160225D02*
X447826Y72702D01*
G01X466438Y160225D02*
X447826Y72702D01*
G01X461840Y160688D02*
X440739Y61312D01*
G01X462978Y160268D02*
X441939Y61186D01*
G01X462978Y160268D02*
X441939Y61186D01*
G01X461840Y160688D02*
X440739Y61312D01*
G01X455888Y161785D02*
X433653Y57211D01*
G01X457016Y161318D02*
X434853Y57084D01*
G01X457016Y161318D02*
X434853Y57084D01*
G01X455888Y161785D02*
X433653Y57211D01*
G01X450023Y162334D02*
X426565Y51968D01*
G01X451147Y161845D02*
X427765Y51841D01*
G01X451147Y161845D02*
X427765Y51841D01*
G01X450023Y162334D02*
X426565Y51968D01*
G01X421875Y68142D02*
X419479Y56873D01*
G01X423003Y67675D02*
X420679Y56746D01*
G01X424787Y72626D02*
X421875Y68142D01*
G01X428585Y76271D02*
X423003Y67675D01*
G01X427457Y76738D02*
X424787Y72626D01*
G01X428585Y76271D02*
X423003Y67675D01*
G01X446305Y165437D02*
X427457Y76738D01*
G01X447429Y164952D02*
X428585Y76271D01*
G01X423003Y67675D02*
X420679Y56746D01*
G01X421875Y68142D02*
X419479Y56873D01*
G01X428585Y76271D02*
X423003Y67675D01*
G01X424787Y72626D02*
X421875Y68142D01*
G01X427457Y76738D02*
X424787Y72626D01*
G01X447429Y164952D02*
X428585Y76271D01*
G01X446305Y165437D02*
X427457Y76738D01*
G01X415177Y65541D02*
X412392Y52441D01*
G01X414949Y58695D02*
X413592Y52314D01*
G01X416305Y65074D02*
X414949Y58695D01*
G01X423859Y78908D02*
X415177Y65541D01*
G01X424987Y78441D02*
X416305Y65074D01*
G01X443055Y169246D02*
X423859Y78908D01*
G01X444160Y168672D02*
X424987Y78441D01*
G01X414949Y58695D02*
X413592Y52314D01*
G01X415177Y65541D02*
X412392Y52441D01*
G01X416305Y65074D02*
X414949Y58695D01*
G01X415177Y65541D02*
X412392Y52441D01*
G01X424987Y78441D02*
X416305Y65074D01*
G01X423859Y78908D02*
X415177Y65541D01*
G01X444160Y168672D02*
X424987Y78441D01*
G01X443055Y169246D02*
X423859Y78908D01*
G01X406941Y60571D02*
X405306Y52879D01*
G01X408069Y60104D02*
X406506Y52752D01*
G01X419963Y80621D02*
X406941Y60571D01*
G01X421091Y80154D02*
X408069Y60104D01*
G01X435876Y155500D02*
X419963Y80621D01*
G01X437103Y155500D02*
X421091Y80154D01*
G01X408069Y60104D02*
X406506Y52752D01*
G01X406941Y60571D02*
X405306Y52879D01*
G01X421091Y80154D02*
X408069Y60104D01*
G01X419963Y80621D02*
X406941Y60571D01*
G01X437103Y155500D02*
X421091Y80154D01*
G01X435876Y155500D02*
X419963Y80621D01*
G01X398982Y56026D02*
X398219Y52435D01*
G01X400110Y55559D02*
X399419Y52308D01*
G01X399103Y56212D02*
X398982Y56026D01*
G01X416426Y80682D02*
X400110Y55559D01*
G01X415298Y81149D02*
X399103Y56212D01*
G01X416426Y80682D02*
X400110Y55559D01*
G01X423001Y117398D02*
X415298Y81149D01*
G01X431931Y153650D02*
X416426Y80682D01*
G01X431931Y153650D02*
X416426Y80682D01*
G01X400110Y55559D02*
X399419Y52308D01*
G01X398982Y56026D02*
X398219Y52435D01*
G01X416426Y80682D02*
X400110Y55559D01*
G01X399103Y56212D02*
X398982Y56026D01*
G01X415298Y81149D02*
X399103Y56212D01*
G01X431931Y153650D02*
X416426Y80682D01*
G01X423001Y117398D02*
X415298Y81149D01*
G01X392899Y59634D02*
X391133Y51326D01*
G01X412018Y89075D02*
X392899Y59634D01*
G01X413146Y88608D02*
X394027Y59167D01*
G01X425517Y152585D02*
X412018Y89075D01*
G01X426744Y152585D02*
X413146Y88608D01*
G01X392899Y59634D02*
X391133Y51326D01*
G01X413146Y88608D02*
X394027Y59167D01*
G01X412018Y89075D02*
X392899Y59634D01*
G01X426744Y152585D02*
X413146Y88608D01*
G01X425517Y152585D02*
X412018Y89075D01*
G01X394918Y118079D02*
X392796Y108093D01*
G01X398215Y127818D02*
X393924Y107626D01*
G01X398215Y127818D02*
X393924Y107626D01*
G01X398215Y127818D02*
X393924Y107626D01*
G01X394918Y118079D02*
X392796Y108093D01*
G01X393377Y131030D02*
X389541Y112976D01*
G01X398443Y149087D02*
X390669Y112509D01*
G01X398443Y149087D02*
X390669Y112509D01*
G01X398443Y149087D02*
X390669Y112509D01*
G01X393377Y131030D02*
X389541Y112976D01*
G01X408967Y93329D02*
X387263Y59910D01*
G01X420515Y153428D02*
X407839Y93796D01*
G01X421742Y153428D02*
X408967Y93329D01*
G01D02*
X387263Y59910D01*
G01X421742Y153428D02*
X408967Y93329D01*
G01X420515Y153428D02*
X407839Y93796D01*
G01X415265Y151589D02*
X404167Y99365D01*
G01X410890Y125228D02*
X405295Y98898D01*
G01X410890Y125228D02*
X405295Y98898D01*
G01X415265Y151589D02*
X404167Y99365D01*
G01X415265Y151589D02*
X404167Y99365D01*
G01X410488Y150927D02*
X400517Y104019D01*
G01X411715Y150927D02*
X401645Y103552D01*
G01X411715Y150927D02*
X401645Y103552D01*
G01X410488Y150927D02*
X400517Y104019D01*
G01X401372Y128234D02*
X396873Y107071D01*
G01X407092Y149371D02*
X398001Y106604D01*
G01X407092Y149371D02*
X398001Y106604D01*
G01X407092Y149371D02*
X398001Y106604D01*
G01X401372Y128234D02*
X396873Y107071D01*
G01X449832Y170532D02*
X446305Y165437D01*
G01X450969Y170065D02*
X447429Y164952D01*
G01X450969Y170065D02*
X447429Y164952D01*
G01X449832Y170532D02*
X446305Y165437D01*
G01X443743Y170231D02*
X443055Y169246D01*
G01X444690Y169490D02*
X444179Y168758D01*
G01X444879Y169760D02*
X444690Y169490D01*
G01X443996Y171659D02*
X443743Y170231D01*
G01X445196Y171553D02*
X444879Y169760D01*
G01X443996Y176270D02*
Y171659D01*
G01X445196Y176404D02*
Y171553D01*
G01X444690Y169490D02*
X444179Y168758D01*
G01X443743Y170231D02*
X443055Y169246D01*
G01X444879Y169760D02*
X444690Y169490D01*
G01X443743Y170231D02*
X443055Y169246D01*
G01X445196Y171553D02*
X444879Y169760D01*
G01X443996Y171659D02*
X443743Y170231D01*
G01X445196Y176404D02*
Y171553D01*
G01X443996Y176270D02*
Y171659D01*
G01X435449Y157507D02*
X435876Y155500D01*
G01X436727Y157269D02*
X437103Y155500D01*
G01X436672Y157528D02*
X436727Y157269D01*
G01X437996Y171945D02*
X435449Y157507D01*
G01X439196Y171839D02*
X436672Y157528D01*
G01X437996Y178416D02*
Y171945D01*
G01X439196Y178418D02*
Y171839D01*
G01X436727Y157269D02*
X437103Y155500D01*
G01X435449Y157507D02*
X435876Y155500D01*
G01X436672Y157528D02*
X436727Y157269D01*
G01X435449Y157507D02*
X435876Y155500D01*
G01X439196Y171839D02*
X436672Y157528D01*
G01X437996Y171945D02*
X435449Y157507D01*
G01X439196Y178418D02*
Y171839D01*
G01X437996Y178416D02*
Y171945D01*
G01X430704Y153650D02*
X423001Y117398D01*
G01X429683Y158458D02*
X430704Y153650D01*
G01X430906Y158479D02*
X431931Y153650D01*
G01X431996Y171497D02*
X429683Y158458D01*
G01X433196Y171391D02*
X430906Y158479D01*
G01X431996Y177313D02*
Y171497D01*
G01X433196Y177208D02*
Y171391D01*
G01X430704Y153650D02*
X423001Y117398D01*
G01X430906Y158479D02*
X431931Y153650D01*
G01X429683Y158458D02*
X430704Y153650D01*
G01X433196Y171391D02*
X430906Y158479D01*
G01X431996Y171497D02*
X429683Y158458D01*
G01X433196Y177208D02*
Y171391D01*
G01X431996Y177313D02*
Y171497D01*
G01X424011Y159670D02*
X425517Y152585D01*
G01X425938Y156378D02*
X426744Y152585D01*
G01X425234Y159691D02*
X425938Y156378D01*
G01X425996Y170931D02*
X424011Y159670D01*
G01X427196Y170826D02*
X425234Y159691D01*
G01X425996Y176996D02*
Y170931D01*
G01X427196Y176890D02*
Y170826D01*
G01X425938Y156378D02*
X426744Y152585D01*
G01X424011Y159670D02*
X425517Y152585D01*
G01X425234Y159691D02*
X425938Y156378D01*
G01X424011Y159670D02*
X425517Y152585D01*
G01X427196Y170826D02*
X425234Y159691D01*
G01X425996Y170931D02*
X424011Y159670D01*
G01X427196Y176890D02*
Y170826D01*
G01X425996Y176996D02*
Y170931D01*
G01X397041Y128067D02*
X394918Y118079D01*
G01X401347Y148326D02*
X397041Y128067D01*
G01X402569Y148303D02*
X398215Y127818D01*
G01X401270Y148764D02*
X401347Y148326D01*
G01X402453Y148971D02*
X402569Y148303D01*
G01X399063Y168195D02*
X402453Y148971D01*
G01X397927Y167724D02*
X401270Y148764D01*
G01X402453Y148971D02*
X402569Y148303D01*
G01X399063Y168195D02*
X402453Y148971D01*
G01X396255Y170109D02*
X397927Y167724D01*
G01X397391Y170580D02*
X399063Y168195D01*
G01X396160Y170649D02*
X396255Y170109D01*
G01X397196Y171687D02*
X397391Y170580D01*
G01X396111Y170926D02*
X396160Y170649D01*
G01X397196Y171687D02*
X397391Y170580D01*
G01X396014Y171479D02*
X396111Y170926D01*
G01X397196Y171687D02*
X397391Y170580D01*
G01X395996Y171582D02*
X396014Y171479D01*
G01X397196Y171687D02*
X397391Y170580D01*
G01X395996Y177209D02*
Y171582D01*
G01X397196Y177103D02*
Y171687D01*
G01X397041Y128067D02*
X394918Y118079D01*
G01X402569Y148303D02*
X398215Y127818D01*
G01X401347Y148326D02*
X397041Y128067D01*
G01X402453Y148971D02*
X402569Y148303D01*
G01X401270Y148764D02*
X401347Y148326D01*
G01X397927Y167724D02*
X401270Y148764D01*
G01X399063Y168195D02*
X402453Y148971D01*
G01X401270Y148764D02*
X401347Y148326D01*
G01X397927Y167724D02*
X401270Y148764D01*
G01X397391Y170580D02*
X399063Y168195D01*
G01X396255Y170109D02*
X397927Y167724D01*
G01X397196Y171687D02*
X397391Y170580D01*
G01X396160Y170649D02*
X396255Y170109D01*
G01X396111Y170926D02*
X396160Y170649D01*
G01X396014Y171479D02*
X396111Y170926D01*
G01X395996Y171582D02*
X396014Y171479D01*
G01X397196Y177103D02*
Y171687D01*
G01X395996Y177209D02*
Y171582D01*
G01X397216Y149087D02*
X393378Y131030D01*
G01X393956Y164428D02*
X397216Y149087D01*
G01X395080Y164916D02*
X398443Y149087D01*
G01X390296Y169657D02*
X393956Y164428D01*
G01X391432Y170128D02*
X395079Y164917D01*
G01X390020Y171219D02*
X390296Y169657D01*
G01X391196Y171464D02*
X391432Y170128D01*
G01X389996Y171358D02*
X390020Y171219D01*
G01X391196Y171464D02*
X391432Y170128D01*
G01X389996Y177173D02*
Y171358D01*
G01X391196Y176817D02*
Y171464D01*
G01X397216Y149087D02*
X393378Y131030D01*
G01X395080Y164916D02*
X398443Y149087D01*
G01X393956Y164428D02*
X397216Y149087D01*
G01X391432Y170128D02*
X395079Y164917D01*
G01X390296Y169657D02*
X393956Y164428D01*
G01X391196Y171464D02*
X391432Y170128D01*
G01X390020Y171219D02*
X390296Y169657D01*
G01X389996Y171358D02*
X390020Y171219D01*
G01X391196Y176817D02*
Y171464D01*
G01X389996Y177173D02*
Y171358D01*
G01X394566Y149279D02*
X387283Y115014D01*
G01X390535Y162459D02*
X393339Y149279D01*
G01X391663Y162927D02*
X394566Y149279D01*
G01X387537Y167074D02*
X390535Y162459D01*
G01X388247Y168185D02*
X391663Y162927D01*
G01X387367Y167335D02*
X387537Y167074D01*
G01X388247Y168185D02*
X391663Y162927D01*
G01X394566Y149279D02*
X387283Y115014D01*
G01X391663Y162927D02*
X394566Y149279D01*
G01X390535Y162459D02*
X393339Y149279D01*
G01X388247Y168185D02*
X391663Y162927D01*
G01X387537Y167074D02*
X390535Y162459D01*
G01X387367Y167335D02*
X387537Y167074D01*
G01X389829Y151095D02*
X387657Y161297D01*
G01X391056Y151095D02*
X388785Y161765D01*
G01X391056Y151095D02*
X388785Y161765D01*
G01X389829Y151095D02*
X387657Y161297D01*
G01X418503Y162898D02*
X420515Y153428D01*
G01X419726Y162921D02*
X421742Y153428D01*
G01X419996Y171366D02*
X418503Y162898D01*
G01X421196Y171261D02*
X419726Y162921D01*
G01X419996Y177209D02*
Y171366D01*
G01X421196Y177103D02*
Y171261D01*
G01X419726Y162921D02*
X421742Y153428D01*
G01X418503Y162898D02*
X420515Y153428D01*
G01X421196Y171261D02*
X419726Y162921D01*
G01X419996Y171366D02*
X418503Y162898D01*
G01X421196Y177103D02*
Y171261D01*
G01X419996Y177209D02*
Y171366D01*
G01X416488Y151568D02*
X410890Y125228D01*
G01X414095Y158229D02*
X415265Y151589D01*
G01X415277Y158437D02*
X416488Y151568D01*
G01X413510Y161547D02*
X414095Y158229D01*
G01X414692Y161755D02*
X415277Y158437D01*
G01X414547Y162584D02*
X414692Y161755D01*
G01X413217Y163206D02*
X413510Y161547D01*
G01X414547Y162584D02*
X414692Y161755D01*
G01X414106Y165076D02*
X414547Y162584D01*
G01X412887Y165076D02*
X413217Y163206D01*
G01X414106Y165076D02*
X414547Y162584D01*
G01X413996Y171366D02*
X412887Y165076D01*
G01X415196Y171261D02*
X414106Y165076D01*
G01X413996Y177209D02*
Y171366D01*
G01X415196Y177103D02*
Y171261D01*
G01X416488Y151568D02*
X410890Y125228D01*
G01X415277Y158437D02*
X416488Y151568D01*
G01X414095Y158229D02*
X415265Y151589D01*
G01X414692Y161755D02*
X415277Y158437D01*
G01X413510Y161547D02*
X414095Y158229D01*
G01X414547Y162584D02*
X414692Y161755D01*
G01X413510Y161547D02*
X414095Y158229D01*
G01X413217Y163206D02*
X413510Y161547D01*
G01X414106Y165076D02*
X414547Y162584D01*
G01X413217Y163206D02*
X413510Y161547D01*
G01X412887Y165076D02*
X413217Y163206D01*
G01X415196Y171261D02*
X414106Y165076D01*
G01X413996Y171366D02*
X412887Y165076D01*
G01X415196Y177103D02*
Y171261D01*
G01X413996Y177209D02*
Y171366D01*
G01X407182Y166481D02*
X410488Y150927D01*
G01X408378Y166627D02*
X411715Y150927D01*
G01X407996Y171366D02*
X407158Y166618D01*
G01X409196Y171261D02*
X408380Y166630D01*
G01X407996Y177209D02*
Y171366D01*
G01X409196Y177103D02*
Y171261D01*
G01X408378Y166627D02*
X411715Y150927D01*
G01X407182Y166481D02*
X410488Y150927D01*
G01X409196Y171261D02*
X408380Y166630D01*
G01X407996Y171366D02*
X407158Y166618D01*
G01X409196Y177103D02*
Y171261D01*
G01X407996Y177209D02*
Y171366D01*
G01X405869Y149392D02*
X401372Y128234D01*
G01X401996Y171380D02*
X405869Y149392D01*
G01X403196Y171485D02*
X407092Y149371D01*
G01X401996Y177209D02*
Y171380D01*
G01X403196Y177103D02*
Y171485D01*
G01X405869Y149392D02*
X401372Y128234D01*
G01X403196Y171485D02*
X407092Y149371D01*
G01X401996Y171380D02*
X405869Y149392D01*
G01X403196Y177103D02*
Y171485D01*
G01X401996Y177209D02*
Y171380D01*
G01X446861Y192597D02*
X455579Y179172D01*
G01X447989Y193064D02*
X451819Y187166D01*
G01X446249Y195479D02*
X446861Y192597D01*
G01X447449Y195606D02*
X447989Y193064D01*
G01X446249Y198913D02*
Y195479D01*
G01X447449Y198913D02*
Y195606D01*
G01X446861Y192597D02*
X455579Y179172D01*
G01X447989Y193064D02*
X451819Y187166D01*
G01X446861Y192597D02*
X455579Y179172D01*
G01X447449Y195606D02*
X447989Y193064D01*
G01X446249Y195479D02*
X446861Y192597D01*
G01X447449Y198913D02*
Y195606D01*
G01X446249Y198913D02*
Y195479D01*
G01X443799Y188158D02*
X449106Y179986D01*
G01X447052Y185355D02*
X450102Y180658D01*
G01X444927Y188625D02*
X445581Y187619D01*
G01X442329Y195076D02*
X443799Y188158D01*
G01X443529Y195203D02*
X444927Y188625D01*
G01X442329Y198982D02*
Y195076D01*
G01X443529Y198982D02*
Y195203D01*
G01X447052Y185355D02*
X450102Y180658D01*
G01X443799Y188158D02*
X449106Y179986D01*
G01X444927Y188625D02*
X445581Y187619D01*
G01X443799Y188158D02*
X449106Y179986D01*
G01X443529Y195203D02*
X444927Y188625D01*
G01X442329Y195076D02*
X443799Y188158D01*
G01X443529Y198982D02*
Y195203D01*
G01X442329Y198982D02*
Y195076D01*
G01X442896Y181474D02*
X443996Y176270D01*
G01X444755Y178504D02*
X445196Y176404D01*
G01X444024Y181941D02*
X444193Y181144D01*
G01X440517Y185136D02*
X442896Y181474D01*
G01X441645Y185604D02*
X444024Y181941D01*
G01X438375Y195210D02*
X440517Y185136D01*
G01X439575Y195337D02*
X441645Y185604D01*
G01X438375Y198913D02*
Y195210D01*
G01X439575Y198913D02*
Y195337D01*
G01X444755Y178504D02*
X445196Y176404D01*
G01X442896Y181474D02*
X443996Y176270D01*
G01X444024Y181941D02*
X444193Y181144D01*
G01X442896Y181474D02*
X443996Y176270D01*
G01X441645Y185604D02*
X444024Y181941D01*
G01X440517Y185136D02*
X442896Y181474D01*
G01X439575Y195337D02*
X441645Y185604D01*
G01X438375Y195210D02*
X440517Y185136D01*
G01X439575Y198913D02*
Y195337D01*
G01X438375Y198913D02*
Y195210D01*
G01X434455Y195415D02*
X437995Y178767D01*
G01X438844Y180547D02*
X439195Y178895D01*
G01X438518Y182078D02*
X438844Y180548D01*
G01X435655Y195542D02*
X437957Y184719D01*
G01X434455Y198982D02*
Y195415D01*
G01X435655Y198982D02*
Y195542D01*
G01X438844Y180547D02*
X439195Y178895D01*
G01X434455Y195415D02*
X437995Y178767D01*
G01X438518Y182078D02*
X438844Y180548D01*
G01X434455Y195415D02*
X437995Y178767D01*
G01X435655Y195542D02*
X437957Y184719D01*
G01X434455Y195415D02*
X437995Y178767D01*
G01X435655Y198982D02*
Y195542D01*
G01X434455Y198982D02*
Y195415D01*
G01X432512Y180245D02*
X431996Y177313D01*
G01X434252Y183200D02*
X433196Y177208D01*
G01X433029Y183179D02*
X432512Y180246D01*
G01X434252Y183200D02*
X433196Y177208D01*
G01X430501Y195072D02*
X433029Y183179D01*
G01X433618Y186180D02*
X434252Y183200D01*
G01X431701Y195199D02*
X433057Y188821D01*
G01X430501Y198913D02*
Y195072D01*
G01X431701Y198913D02*
Y195199D01*
G01X434252Y183200D02*
X433196Y177208D01*
G01X432512Y180245D02*
X431996Y177313D01*
G01X433029Y183179D02*
X432512Y180246D01*
G01X433618Y186180D02*
X434252Y183200D01*
G01X430501Y195072D02*
X433029Y183179D01*
G01X431701Y195199D02*
X433057Y188821D01*
G01X430501Y195072D02*
X433029Y183179D01*
G01X431701Y198913D02*
Y195199D01*
G01X430501Y198913D02*
Y195072D01*
G01X427983Y188255D02*
X425996Y176996D01*
G01X429206Y188276D02*
X427196Y176890D01*
G01X426581Y194856D02*
X427983Y188255D01*
G01X428886Y189785D02*
X429206Y188276D01*
G01X427781Y194983D02*
X428324Y192426D01*
G01X426581Y198982D02*
Y194856D01*
G01X427781Y198982D02*
Y194983D01*
G01X429206Y188276D02*
X427196Y176890D01*
G01X427983Y188255D02*
X425996Y176996D01*
G01X428886Y189785D02*
X429206Y188276D01*
G01X426581Y194856D02*
X427983Y188255D01*
G01X427781Y194983D02*
X428324Y192426D01*
G01X426581Y194856D02*
X427983Y188255D01*
G01X427781Y198982D02*
Y194983D01*
G01X426581Y198982D02*
Y194856D01*
G01X396269Y178758D02*
X395996Y177209D01*
G01X397405Y178288D02*
X397196Y177103D01*
G01X396676Y179340D02*
X396269Y178758D01*
G01X397799Y178851D02*
X397405Y178288D01*
G01X397093Y181301D02*
X396676Y179340D01*
G01X398221Y180834D02*
X397799Y178851D01*
G01X406601Y195949D02*
X397093Y181301D01*
G01X405309Y191754D02*
X398221Y180834D01*
G01X407729Y195481D02*
X406779Y194019D01*
G01X406879Y197253D02*
X406601Y195949D01*
G01X408079Y197126D02*
X407729Y195481D01*
G01X406879Y198913D02*
Y197253D01*
G01X408079Y198913D02*
Y197126D01*
G01X397405Y178288D02*
X397196Y177103D01*
G01X396269Y178758D02*
X395996Y177209D01*
G01X397799Y178851D02*
X397405Y178288D01*
G01X396676Y179340D02*
X396269Y178758D01*
G01X398221Y180834D02*
X397799Y178851D01*
G01X397093Y181301D02*
X396676Y179340D01*
G01X405309Y191754D02*
X398221Y180834D01*
G01X406601Y195949D02*
X397093Y181301D01*
G01X407729Y195481D02*
X406779Y194019D01*
G01X406601Y195949D02*
X397093Y181301D01*
G01X408079Y197126D02*
X407729Y195481D01*
G01X406879Y197253D02*
X406601Y195949D01*
G01X408079Y198913D02*
Y197126D01*
G01X406879Y198913D02*
Y197253D01*
G01X390971Y178674D02*
X389996Y177173D01*
G01X392760Y179222D02*
X391196Y176817D01*
G01X402959Y197133D02*
X390968Y178675D01*
G01X404159Y196777D02*
X394231Y181488D01*
G01X402959Y198982D02*
Y197133D01*
G01X404159Y198982D02*
Y196777D01*
G01X392760Y179222D02*
X391196Y176817D01*
G01X390971Y178674D02*
X389996Y177173D01*
G01X404159Y196777D02*
X394231Y181488D01*
G01X402959Y197133D02*
X390968Y178675D01*
G01X404159Y198982D02*
Y196777D01*
G01X402959Y198982D02*
Y197133D01*
G01X392419Y188919D02*
X388195Y182409D01*
G01X391235Y184888D02*
X389077Y181560D01*
G01X393358Y188159D02*
X392705Y187152D01*
G01X396590Y193090D02*
X392419Y188919D01*
G01X397529Y192330D02*
X393358Y188159D01*
G01X398814Y196515D02*
X396590Y193090D01*
G01X399942Y196047D02*
X397529Y192330D01*
G01X399005Y197412D02*
X398814Y196515D01*
G01X400205Y197285D02*
X399942Y196047D01*
G01X399005Y198913D02*
Y197412D01*
G01X400205Y198913D02*
Y197285D01*
G01X391235Y184888D02*
X389077Y181560D01*
G01X392419Y188919D02*
X388195Y182409D01*
G01X393358Y188159D02*
X392705Y187152D01*
G01X392419Y188919D02*
X388195Y182409D01*
G01X397529Y192330D02*
X393358Y188159D01*
G01X396590Y193090D02*
X392419Y188919D01*
G01X399942Y196047D02*
X397529Y192330D01*
G01X398814Y196515D02*
X396590Y193090D01*
G01X400205Y197285D02*
X399942Y196047D01*
G01X399005Y197412D02*
X398814Y196515D01*
G01X400205Y198913D02*
Y197285D01*
G01X399005Y198913D02*
Y197412D01*
G01X395079Y198113D02*
Y199348D01*
G01X396279Y197986D02*
Y199348D01*
G01X394942Y197471D02*
X395079Y198113D01*
G01X396070Y197004D02*
X396279Y197986D01*
G01X393279Y194907D02*
X394942Y197471D01*
G01X394147Y194039D02*
X396070Y197004D01*
G01X392235Y192798D02*
X394147Y194039D01*
G01X396279Y197986D02*
Y199348D01*
G01X395079Y198113D02*
Y199348D01*
G01X396070Y197004D02*
X396279Y197986D01*
G01X394942Y197471D02*
X395079Y198113D01*
G01X394147Y194039D02*
X396070Y197004D01*
G01X393279Y194907D02*
X394942Y197471D01*
G01X392235Y192798D02*
X394147Y194039D01*
G01X420269Y178759D02*
X419996Y177209D01*
G01X421405Y178288D02*
X421196Y177103D01*
G01X421189Y180074D02*
X420269Y178759D01*
G01X422345Y179633D02*
X421405Y178288D01*
G01X423399Y190338D02*
X421227Y180130D01*
G01X423815Y186522D02*
X422358Y179672D01*
G01X424626Y190338D02*
X424376Y189163D01*
G01X422627Y193966D02*
X423399Y190338D01*
G01X423827Y194093D02*
X424626Y190338D01*
G01X422627Y198913D02*
Y193966D01*
G01X423827Y198913D02*
Y194093D01*
G01X421405Y178288D02*
X421196Y177103D01*
G01X420269Y178759D02*
X419996Y177209D01*
G01X422345Y179633D02*
X421405Y178288D01*
G01X421189Y180074D02*
X420269Y178759D01*
G01X423815Y186522D02*
X422358Y179672D01*
G01X423399Y190338D02*
X421227Y180130D01*
G01X424626Y190338D02*
X424376Y189163D01*
G01X423399Y190338D02*
X421227Y180130D01*
G01X423827Y194093D02*
X424626Y190338D01*
G01X422627Y193966D02*
X423399Y190338D01*
G01X423827Y198913D02*
Y194093D01*
G01X422627Y198913D02*
Y193966D01*
G01X414269Y178758D02*
X413996Y177209D01*
G01X415405Y178288D02*
X415196Y177103D01*
G01X415230Y180132D02*
X414269Y178758D01*
G01X416366Y179662D02*
X415405Y178288D01*
G01X415339Y180752D02*
X415230Y180132D01*
G01X416517Y180519D02*
X416366Y179662D01*
G01X417241Y183926D02*
X416517Y180519D01*
G01X418707Y196589D02*
X415339Y180752D01*
G01X417241Y183926D02*
X416517Y180519D01*
G01X419907Y196462D02*
X417803Y186567D01*
G01X418707Y198982D02*
Y196589D01*
G01X419907Y198982D02*
Y196462D01*
G01X415405Y178288D02*
X415196Y177103D01*
G01X414269Y178758D02*
X413996Y177209D01*
G01X416366Y179662D02*
X415405Y178288D01*
G01X415230Y180132D02*
X414269Y178758D01*
G01X416517Y180519D02*
X416366Y179662D01*
G01X415339Y180752D02*
X415230Y180132D01*
G01X417241Y183926D02*
X416517Y180519D01*
G01X415339Y180752D02*
X415230Y180132D01*
G01X418707Y196589D02*
X415339Y180752D01*
G01X419907Y196462D02*
X417803Y186567D01*
G01X418707Y196589D02*
X415339Y180752D01*
G01X419907Y198982D02*
Y196462D01*
G01X418707Y198982D02*
Y196589D01*
G01X408269Y178758D02*
X407996Y177209D01*
G01X409405Y178288D02*
X409196Y177103D01*
G01X408824Y179551D02*
X408269Y178758D01*
G01X410355Y179644D02*
X409405Y178288D01*
G01X409227Y180125D02*
X408824Y179551D01*
G01X410355Y179644D02*
X409405Y178288D01*
G01X410660Y186869D02*
X409230Y180144D01*
G01X410977Y182586D02*
X410374Y179754D01*
G01X411788Y186402D02*
X411538Y185227D01*
G01X414004Y192018D02*
X410660Y186869D01*
G01X415132Y191551D02*
X411788Y186402D01*
G01X414753Y195543D02*
X414004Y192018D01*
G01X415953Y195416D02*
X415132Y191551D01*
G01X414753Y198913D02*
Y195543D01*
G01X415953Y198913D02*
Y195416D01*
G01X409405Y178288D02*
X409196Y177103D01*
G01X408269Y178758D02*
X407996Y177209D01*
G01X410355Y179644D02*
X409405Y178288D01*
G01X408824Y179551D02*
X408269Y178758D01*
G01X409227Y180125D02*
X408824Y179551D01*
G01X410977Y182586D02*
X410374Y179754D01*
G01X410660Y186869D02*
X409230Y180144D01*
G01X411788Y186402D02*
X411538Y185227D01*
G01X410660Y186869D02*
X409230Y180144D01*
G01X415132Y191551D02*
X411788Y186402D01*
G01X414004Y192018D02*
X410660Y186869D01*
G01X415953Y195416D02*
X415132Y191551D01*
G01X414753Y195543D02*
X414004Y192018D01*
G01X415953Y198913D02*
Y195416D01*
G01X414753Y198913D02*
Y195543D01*
G01X402096Y177772D02*
X401996Y177209D01*
G01X403405Y178288D02*
X403196Y177103D01*
G01X402269Y178759D02*
X402096Y177772D01*
G01X403405Y178288D02*
X403196Y177103D01*
G01X403224Y180122D02*
X402269Y178759D01*
G01X404348Y179633D02*
X403405Y178288D01*
G01X404312Y185248D02*
X403224Y180122D01*
G01X404630Y180966D02*
X404348Y179633D01*
G01X405441Y184782D02*
X405191Y183607D01*
G01X410326Y194508D02*
X404312Y185248D01*
G01X411454Y194041D02*
X405441Y184782D01*
G01X410833Y196896D02*
X410326Y194508D01*
G01X412033Y196770D02*
X411454Y194041D01*
G01X410833Y198982D02*
Y196896D01*
G01X412033Y198982D02*
Y196770D01*
G01X403405Y178288D02*
X403196Y177103D01*
G01X402096Y177772D02*
X401996Y177209D01*
G01X402269Y178759D02*
X402096Y177772D01*
G01X404348Y179633D02*
X403405Y178288D01*
G01X403224Y180122D02*
X402269Y178759D01*
G01X404630Y180966D02*
X404348Y179633D01*
G01X404312Y185248D02*
X403224Y180122D01*
G01X405441Y184782D02*
X405191Y183607D01*
G01X404312Y185248D02*
X403224Y180122D01*
G01X411454Y194041D02*
X405441Y184782D01*
G01X410326Y194508D02*
X404312Y185248D01*
G01X412033Y196770D02*
X411454Y194041D01*
G01X410833Y196896D02*
X410326Y194508D01*
G01X412033Y198982D02*
Y196770D01*
G01X410833Y198982D02*
Y196896D01*
G01X405060Y423572D02*
X405539Y424051D01*
G01X404480Y422172D02*
G02X405060Y423572I1980J0D01*
G01X404211Y424421D02*
G03X403280Y422173I2249J-2248D01*
G01X404480Y421252D02*
Y422172D01*
G01X403280Y422173D02*
Y421079D01*
G01X405267Y418572D02*
X404480Y421252D01*
G01X403280Y421079D02*
X404240Y417807D01*
G01X407532Y417103D02*
X405267Y418572D01*
G01X404240Y417807D02*
X407065Y415975D01*
G01X410364Y416500D02*
X407532Y417103D01*
G01X409799Y415393D02*
X410237Y415300D01*
G01X408698Y415627D02*
X409799Y415393D01*
G01X407065Y415975D02*
X408698Y415627D01*
G01X428041Y416500D02*
X410364D01*
G01X410237Y415300D02*
X427914D01*
G01X409799Y415393D02*
X410237Y415300D01*
G01X457854Y410162D02*
X428041Y416500D01*
G01X427914Y415300D02*
X457854Y408935D01*
G01X427914Y415300D02*
X457854Y408935D01*
G01Y410162D02*
X428041Y416500D01*
G01X410237Y415300D02*
X427914D01*
G01X428041Y416500D02*
X410364D01*
G01X409799Y415393D02*
X410237Y415300D01*
G01X410364Y416500D02*
X407532Y417103D01*
G01X428041Y416500D02*
X410364D01*
G01X408698Y415627D02*
X409799Y415393D01*
G01X410364Y416500D02*
X407532Y417103D01*
G01X407065Y415975D02*
X408698Y415627D01*
G01X410364Y416500D02*
X407532Y417103D01*
G01X404240Y417807D02*
X407065Y415975D01*
G01X407532Y417103D02*
X405267Y418572D01*
G01X403280Y421079D02*
X404240Y417807D01*
G01X405267Y418572D02*
X404480Y421252D01*
G01X403280Y422173D02*
Y421079D01*
G01X404480Y421252D02*
Y422172D01*
G01X404211Y424421D02*
G03X403280Y422173I2249J-2248D01*
G01X404480Y422172D02*
G02X405060Y423572I1980J0D01*
G01D02*
X405539Y424051D01*
G01X405060Y423572D02*
X405539Y424051D01*
G01X413459Y421679D02*
G02X414492Y424121I2031J581D01*
G01X412365Y421159D02*
G02X413928Y425181I3124J1101D01*
G01X414174Y420577D02*
X413459Y421679D01*
G01X413305Y419709D02*
X412365Y421159D01*
G01X414968Y420061D02*
X414174Y420577D01*
G01X414506Y418930D02*
X413305Y419709D01*
G01X416398Y419772D02*
X414968Y420061D01*
G01X415445Y418739D02*
X414506Y418930D01*
G01X416162Y418595D02*
X415445Y418739D01*
G01X416277Y418572D02*
X416162Y418595D01*
G01X431175Y419772D02*
X416398D01*
G01X416162Y418595D02*
X415445Y418739D01*
G01X416277Y418572D02*
X416162Y418595D01*
G01X431048Y418572D02*
X416277D01*
G01X458209Y414024D02*
X431175Y419772D01*
G01X458209Y412797D02*
X431048Y418572D01*
G01X412365Y421159D02*
G02X413928Y425181I3124J1101D01*
G01X413459Y421679D02*
G02X414492Y424121I2031J581D01*
G01X413305Y419709D02*
X412365Y421159D01*
G01X414174Y420577D02*
X413459Y421679D01*
G01X414506Y418930D02*
X413305Y419709D01*
G01X414968Y420061D02*
X414174Y420577D01*
G01X415445Y418739D02*
X414506Y418930D01*
G01X416398Y419772D02*
X414968Y420061D01*
G01X416162Y418595D02*
X415445Y418739D01*
G01X416398Y419772D02*
X414968Y420061D01*
G01X431175Y419772D02*
X416398D01*
G01X416277Y418572D02*
X416162Y418595D01*
G01X416398Y419772D02*
X414968Y420061D01*
G01X431175Y419772D02*
X416398D01*
G01X431048Y418572D02*
X416277D01*
G01X431175Y419772D02*
X416398D01*
G01X458209Y412797D02*
X431048Y418572D01*
G01X458209Y414024D02*
X431175Y419772D01*
G01X405633Y409160D02*
X405934Y409321D01*
G01X405275Y410330D02*
X405367Y410379D01*
G01X405066Y410218D02*
X405275Y410330D01*
G01X405539Y409090D02*
G02X405633Y409160I283J-282D01*
G01X404689Y409938D02*
G02X405066Y410218I1132J-1130D01*
G01X404470Y405229D02*
G02X405539Y409090I3943J987D01*
G01X403361Y404732D02*
G02X404689Y409938I5052J1484D01*
G01X405886Y403048D02*
X404470Y405229D01*
G01X405018Y402180D02*
X403361Y404732D01*
G01X408705Y401217D02*
X405886Y403048D01*
G01X408238Y400089D02*
X405018Y402180D01*
G01X416392Y399584D02*
X408705Y401217D01*
G01X412300Y399226D02*
X408238Y400089D01*
G01X416142Y398409D02*
X412300Y399225D01*
G01X416146Y398408D02*
X416142Y398409D01*
G01X416396Y399583D02*
X416392Y399584D01*
G01X416142Y398409D02*
X412300Y399225D01*
G01X422337Y397093D02*
X416149Y398407D01*
G01X422337Y398320D02*
X416399Y399582D01*
G01X416146Y398408D02*
X416142Y398409D01*
G01X422337Y397093D02*
X416149Y398407D01*
G01X439253Y401917D02*
X422337Y398320D01*
G01X439253Y400690D02*
X422337Y397093D01*
G01X446964Y400279D02*
X439253Y401917D01*
G01X446964Y399052D02*
X439253Y400690D01*
G01X468267Y404808D02*
X446964Y400279D01*
G01X468267Y403581D02*
X446964Y399052D01*
G01X405275Y410330D02*
X405367Y410379D01*
G01X405633Y409160D02*
X405934Y409321D01*
G01X405066Y410218D02*
X405275Y410330D01*
G01X405633Y409160D02*
X405934Y409321D01*
G01X404689Y409938D02*
G02X405066Y410218I1132J-1130D01*
G01X405539Y409090D02*
G02X405633Y409160I283J-282D01*
G01X403361Y404732D02*
G02X404689Y409938I5052J1484D01*
G01X404470Y405229D02*
G02X405539Y409090I3943J987D01*
G01X405018Y402180D02*
X403361Y404732D01*
G01X405886Y403048D02*
X404470Y405229D01*
G01X408238Y400089D02*
X405018Y402180D01*
G01X408705Y401217D02*
X405886Y403048D01*
G01X412300Y399226D02*
X408238Y400089D01*
G01X416392Y399584D02*
X408705Y401217D01*
G01X416142Y398409D02*
X412300Y399225D01*
G01X416392Y399584D02*
X408705Y401217D01*
G01X416396Y399583D02*
X416392Y399584D01*
G01X416146Y398408D02*
X416142Y398409D01*
G01X416392Y399584D02*
X408705Y401217D01*
G01X422337Y398320D02*
X416399Y399582D01*
G01X422337Y397093D02*
X416149Y398407D01*
G01X416396Y399583D02*
X416392Y399584D01*
G01X422337Y398320D02*
X416399Y399582D01*
G01X439253Y400690D02*
X422337Y397093D01*
G01X439253Y401917D02*
X422337Y398320D01*
G01X446964Y399052D02*
X439253Y400690D01*
G01X446964Y400279D02*
X439253Y401917D01*
G01X468267Y403581D02*
X446964Y399052D01*
G01X468267Y404808D02*
X446964Y400279D01*
G01X446953Y404025D02*
X470754Y409085D01*
G01Y407858D02*
X446953Y402798D01*
G01X436762Y406192D02*
X446953Y404025D01*
G01Y402798D02*
X436762Y404965D01*
G01X420095Y402648D02*
X436762Y406192D01*
G01Y404965D02*
X420095Y401421D01*
G01X415605Y403604D02*
X420095Y402648D01*
G01Y401421D02*
X415138Y402476D01*
G01X414047Y404616D02*
X415605Y403604D01*
G01X414173Y403103D02*
X413178Y403748D01*
G01X415138Y402476D02*
X414173Y403103D01*
G01X413488Y405478D02*
X414047Y404616D01*
G01X413178Y403748D02*
X412360Y405011D01*
G01X413247Y406612D02*
X413488Y405478D01*
G01X412360Y405011D02*
X412047Y406485D01*
G01X413247Y407026D02*
Y406612D01*
G01X412047Y406485D02*
Y407026D01*
G01X413918Y408611D02*
G03X413247Y407026I1537J-1585D01*
G01X412047D02*
G02X413075Y409466I3408J1D01*
G01X414397Y409090D02*
X413918Y408611D01*
G01X413308Y409699D02*
X413547Y409939D01*
G01X413075Y409466D02*
X413308Y409699D01*
G01X414491Y409160D02*
G03X414397Y409090I189J-352D01*
G01X413547Y409939D02*
G02X413924Y410218I1130J-1133D01*
G01X414792Y409321D02*
X414491Y409160D01*
G01X414133Y410330D02*
X414225Y410379D01*
G01X413924Y410218D02*
X414133Y410330D01*
G01D02*
X414225Y410379D01*
G01X414792Y409321D02*
X414491Y409160D01*
G01X413924Y410218D02*
X414133Y410330D01*
G01X414792Y409321D02*
X414491Y409160D01*
G01X413547Y409939D02*
G02X413924Y410218I1130J-1133D01*
G01X414491Y409160D02*
G03X414397Y409090I189J-352D01*
G01X413308Y409699D02*
X413547Y409939D01*
G01X414397Y409090D02*
X413918Y408611D01*
G01X413075Y409466D02*
X413308Y409699D01*
G01X414397Y409090D02*
X413918Y408611D01*
G01X412047Y407026D02*
G02X413075Y409466I3408J1D01*
G01X413918Y408611D02*
G03X413247Y407026I1537J-1585D01*
G01X412047Y406485D02*
Y407026D01*
G01X413247D02*
Y406612D01*
G01X412360Y405011D02*
X412047Y406485D01*
G01X413247Y406612D02*
X413488Y405478D01*
G01X413178Y403748D02*
X412360Y405011D01*
G01X413488Y405478D02*
X414047Y404616D01*
G01X414173Y403103D02*
X413178Y403748D01*
G01X414047Y404616D02*
X415605Y403604D01*
G01X415138Y402476D02*
X414173Y403103D01*
G01X414047Y404616D02*
X415605Y403604D01*
G01X420095Y401421D02*
X415138Y402476D01*
G01X415605Y403604D02*
X420095Y402648D01*
G01X436762Y404965D02*
X420095Y401421D01*
G01Y402648D02*
X436762Y406192D01*
G01X446953Y402798D02*
X436762Y404965D01*
G01Y406192D02*
X446953Y404025D01*
G01X470754Y407858D02*
X446953Y402798D01*
G01Y404025D02*
X470754Y409085D01*
G01X405633Y424121D02*
X405934Y424282D01*
G01X405275Y425291D02*
X405066Y425179D01*
G01X405367Y425340D02*
X405275Y425291D01*
G01X405539Y424051D02*
G02X405633Y424121I283J-282D01*
G01X405066Y425179D02*
G03X404689Y424900I753J-1412D01*
G01X404450Y424660D02*
X404211Y424421D01*
G01X404689Y424900D02*
X404450Y424660D01*
G01D02*
X404211Y424421D01*
G01X404689Y424900D02*
X404450Y424660D01*
G01X405066Y425179D02*
G03X404689Y424900I753J-1412D01*
G01X405539Y424051D02*
G02X405633Y424121I283J-282D01*
G01X405275Y425291D02*
X405066Y425179D01*
G01X405633Y424121D02*
X405934Y424282D01*
G01X405367Y425340D02*
X405275Y425291D01*
G01X405633Y424121D02*
X405934Y424282D01*
G01X414716Y424241D02*
X414786Y424278D01*
G01X413928Y425181D02*
X414133Y425291D01*
G01X414707Y424236D02*
X414716Y424241D01*
G01X413928Y425181D02*
X414133Y425291D01*
G01X414703Y424234D02*
X414707Y424236D01*
G01X413928Y425181D02*
X414133Y425291D01*
G01X414492Y424121D02*
X414700Y424232D01*
G01X414142Y425296D02*
X414150Y425300D01*
G01X414133Y425291D02*
X414134D01*
G01X413928Y425181D02*
X414133Y425291D01*
G01X414142Y425296D02*
X414150Y425300D01*
G01X414492Y424121D02*
X414700Y424232D01*
G01X414133Y425291D02*
X414134D01*
G01X414492Y424121D02*
X414700Y424232D01*
G01X413928Y425181D02*
X414133Y425291D01*
G01X414716Y424241D02*
X414786Y424278D01*
G01X414707Y424236D02*
X414716Y424241D01*
G01X414703Y424234D02*
X414707Y424236D01*
G01X414492Y424121D02*
X414700Y424232D01*
G01X499493Y40739D02*
X500869D01*
G01X499493Y41939D02*
X500869D01*
G01X497432Y42800D02*
G03X499493Y40739I2061J0D01*
G01X498632Y42800D02*
G03X499493Y41939I861J0D01*
G01X497432Y59406D02*
Y42800D01*
G01X498632Y59279D02*
Y42800D01*
G01X499493Y41939D02*
X500869D01*
G01X499493Y40739D02*
X500869D01*
G01X498632Y42800D02*
G03X499493Y41939I861J0D01*
G01X497432Y42800D02*
G03X499493Y40739I2061J0D01*
G01X498632Y59279D02*
Y42800D01*
G01X497432Y59406D02*
Y42800D01*
G01X490346Y47524D02*
Y55379D01*
G01X491546Y55253D02*
Y47524D01*
G01X492407Y45463D02*
G02X490346Y47524I0J2061D01*
G01X491546D02*
G03X492407Y46663I861J0D01*
G01X493783Y45463D02*
X492407D01*
G01Y46663D02*
X493783D01*
G01X492407D02*
X493783D01*
G01Y45463D02*
X492407D01*
G01X491546Y47524D02*
G03X492407Y46663I861J0D01*
G01Y45463D02*
G02X490346Y47524I0J2061D01*
G01X491546Y55253D02*
Y47524D01*
G01X490346D02*
Y55379D01*
G01X485320Y40739D02*
X486696D01*
G01X485320Y41939D02*
X486696D01*
G01X483258Y42801D02*
G03X485320Y40739I2062J0D01*
G01X484458Y42801D02*
G03X485320Y41939I862J0D01*
G01X483258Y51330D02*
Y42801D01*
G01X484458Y51203D02*
Y42801D01*
G01X487265Y64409D02*
X484458Y51203D01*
G01X485320Y41939D02*
X486696D01*
G01X485320Y40739D02*
X486696D01*
G01X484458Y42801D02*
G03X485320Y41939I862J0D01*
G01X483258Y42801D02*
G03X485320Y40739I2062J0D01*
G01X484458Y51203D02*
Y42801D01*
G01X483258Y51330D02*
Y42801D01*
G01X487265Y64409D02*
X484458Y51203D01*
G01X478233Y45463D02*
X479609D01*
G01X478233Y46663D02*
X479609D01*
G01X476172Y47524D02*
G03X478233Y45463I2061J0D01*
G01X477372Y47524D02*
G03X478233Y46663I861J0D01*
G01X476172Y53330D02*
Y47524D01*
G01X477372Y53203D02*
Y47524D01*
G01X478233Y46663D02*
X479609D01*
G01X478233Y45463D02*
X479609D01*
G01X477372Y47524D02*
G03X478233Y46663I861J0D01*
G01X476172Y47524D02*
G03X478233Y45463I2061J0D01*
G01X477372Y53203D02*
Y47524D01*
G01X476172Y53330D02*
Y47524D01*
G01X469085Y42801D02*
Y63484D01*
G01X470285Y42801D02*
Y63357D01*
G01X471147Y40739D02*
G02X469085Y42801I0J2062D01*
G01X471147Y41939D02*
G02X470285Y42801I0J862D01*
G01X472523Y40739D02*
X471147D01*
G01X472523Y41939D02*
X471147D01*
G01X470285Y42801D02*
Y63357D01*
G01X469085Y42801D02*
Y63484D01*
G01X471147Y41939D02*
G02X470285Y42801I0J862D01*
G01X471147Y40739D02*
G02X469085Y42801I0J2062D01*
G01X472523Y41939D02*
X471147D01*
G01X472523Y40739D02*
X471147D01*
G01X464060Y45463D02*
X465436D01*
G01X464060Y46663D02*
X465436D01*
G01X461999Y47524D02*
G03X464060Y45463I2061J0D01*
G01X463199Y47524D02*
G03X464060Y46663I861J0D01*
G01X461999Y59658D02*
Y47524D01*
G01X463199Y59531D02*
Y47524D01*
G01X464060Y46663D02*
X465436D01*
G01X464060Y45463D02*
X465436D01*
G01X463199Y47524D02*
G03X464060Y46663I861J0D01*
G01X461999Y47524D02*
G03X464060Y45463I2061J0D01*
G01X463199Y59531D02*
Y47524D01*
G01X461999Y59658D02*
Y47524D01*
G01X454912Y42800D02*
Y83758D01*
G01X456112Y42800D02*
Y83631D01*
G01X456973Y40739D02*
G02X454912Y42800I0J2061D01*
G01X456973Y41939D02*
G02X456112Y42800I0J861D01*
G01X458349Y40739D02*
X456973D01*
G01X458349Y41939D02*
X456973D01*
G01X456112Y42800D02*
Y83631D01*
G01X454912Y42800D02*
Y83758D01*
G01X456973Y41939D02*
G02X456112Y42800I0J861D01*
G01X456973Y40739D02*
G02X454912Y42800I0J2061D01*
G01X458349Y41939D02*
X456973D01*
G01X458349Y40739D02*
X456973D01*
G01X449887Y46663D02*
X451263D01*
G01X449887Y45463D02*
X451263D01*
G01X449026Y47524D02*
G03X449887Y46663I861J0D01*
G01X449026Y72575D02*
Y47524D01*
G01X504519D02*
Y60261D01*
G01X505719Y60134D02*
Y47524D01*
G01X506580Y45463D02*
G02X504519Y47524I0J2061D01*
G01X505719D02*
G03X506580Y46663I861J0D01*
G01X507956Y45463D02*
X506580D01*
G01Y46663D02*
X507956D01*
G01X506580D02*
X507956D01*
G01Y45463D02*
X506580D01*
G01X505719Y47524D02*
G03X506580Y46663I861J0D01*
G01Y45463D02*
G02X504519Y47524I0J2061D01*
G01X505719Y60134D02*
Y47524D01*
G01X504519D02*
Y60261D01*
G01X449887Y45463D02*
X451263D01*
G01X449887Y46663D02*
X451263D01*
G01X449026Y47524D02*
G03X449887Y46663I861J0D01*
G01X449026Y72575D02*
Y47524D01*
G01X523820Y183556D02*
X497432Y59406D01*
G01X525047Y183556D02*
X498632Y59279D01*
G01X525047Y183556D02*
X498632Y59279D01*
G01X523820Y183556D02*
X497432Y59406D01*
G01X491155Y76628D02*
X512872Y178811D01*
G01X513943Y178075D02*
X492382Y76628D01*
G01X493007Y67914D02*
X491155Y76628D01*
G01X492382D02*
X494234Y67914D01*
G01X491676Y61645D02*
X493007Y67914D01*
G01X494234D02*
X491546Y55253D01*
G01X490346Y55379D02*
X491675Y61645D01*
G01X494234Y67914D02*
X491546Y55253D01*
G01X494234Y67914D02*
X491546Y55253D01*
G01X491676Y61645D02*
X493007Y67914D01*
G01X490346Y55379D02*
X491675Y61645D01*
G01X492382Y76628D02*
X494234Y67914D01*
G01X493007D02*
X491155Y76628D01*
G01X513943Y178075D02*
X492382Y76628D01*
G01X491155D02*
X512872Y178811D01*
G01X486038Y64409D02*
X483258Y51330D01*
G01X481509Y85717D02*
X486038Y64409D01*
G01X482736Y85716D02*
X487265Y64409D01*
G01X497567Y161266D02*
X481509Y85717D01*
G01X498695Y160799D02*
X482736Y85716D01*
G01X486038Y64409D02*
X483258Y51330D01*
G01X482736Y85716D02*
X487265Y64409D01*
G01X481509Y85717D02*
X486038Y64409D01*
G01X498695Y160799D02*
X482736Y85716D01*
G01X497567Y161266D02*
X481509Y85717D01*
G01X478421Y63912D02*
X476172Y53330D01*
G01X479648Y63912D02*
X477372Y53203D01*
G01X474124Y84127D02*
X478421Y63912D01*
G01X475351Y84127D02*
X479648Y63912D01*
G01X491470Y165733D02*
X474124Y84127D01*
G01X492598Y165266D02*
X475351Y84127D01*
G01X479648Y63912D02*
X477372Y53203D01*
G01X478421Y63912D02*
X476172Y53330D01*
G01X475351Y84127D02*
X479648Y63912D01*
G01X474124Y84127D02*
X478421Y63912D01*
G01X492598Y165266D02*
X475351Y84127D01*
G01X491470Y165733D02*
X474124Y84127D01*
G01X467859Y88545D02*
X486296Y175234D01*
G01X469086Y88545D02*
X487496Y175107D01*
G01X471136Y73135D02*
X467859Y88545D01*
G01X472363Y73135D02*
X469086Y88545D01*
G01X469085Y63484D02*
X471136Y73135D01*
G01X470285Y63357D02*
X472363Y73135D01*
G01X469086Y88545D02*
X487496Y175107D01*
G01X467859Y88545D02*
X486296Y175234D01*
G01X472363Y73135D02*
X469086Y88545D01*
G01X471136Y73135D02*
X467859Y88545D01*
G01X470285Y63357D02*
X472363Y73135D01*
G01X469085Y63484D02*
X471136Y73135D01*
G01X464516Y71496D02*
X461999Y59658D01*
G01X465743Y71496D02*
X463199Y59531D01*
G01X460580Y90009D02*
X464516Y71496D01*
G01X461807Y90009D02*
X465743Y71496D01*
G01X475185Y158705D02*
X460580Y90009D01*
G01X476313Y158238D02*
X461807Y90009D01*
G01X465743Y71496D02*
X463199Y59531D01*
G01X464516Y71496D02*
X461999Y59658D01*
G01X461807Y90009D02*
X465743Y71496D01*
G01X460580Y90009D02*
X464516Y71496D01*
G01X476313Y158238D02*
X461807Y90009D01*
G01X475185Y158705D02*
X460580Y90009D01*
G01X454912Y83758D02*
X471114Y159987D01*
G01X456112Y83631D02*
X471431Y155705D01*
G01X454912Y83758D02*
X471114Y159987D01*
G01X456112Y83631D02*
X471431Y155705D01*
G01X454912Y83758D02*
X471114Y159987D01*
G01X467566Y159758D02*
X449026Y72575D01*
G01X504519Y60261D02*
X529513Y177871D01*
G01X530740D02*
X505719Y60134D01*
G01X530740Y177871D02*
X505719Y60134D01*
G01X504519Y60261D02*
X529513Y177871D01*
G01X467566Y159758D02*
X449026Y72575D01*
G01X502785Y169300D02*
X497567Y161266D01*
G01X503913Y168833D02*
X498695Y160799D01*
G01X505305Y181160D02*
X502785Y169300D01*
G01X506532Y181160D02*
X503913Y168833D01*
G01D02*
X498695Y160799D01*
G01X502785Y169300D02*
X497567Y161266D01*
G01X506532Y181160D02*
X503913Y168833D01*
G01X505305Y181160D02*
X502785Y169300D01*
G01X493192Y168386D02*
X491470Y165733D01*
G01X494320Y167918D02*
X492598Y165266D01*
G01X495378Y178639D02*
X493192Y168386D01*
G01X496605Y178638D02*
X494320Y167918D01*
G01D02*
X492598Y165266D01*
G01X493192Y168386D02*
X491470Y165733D01*
G01X496605Y178638D02*
X494320Y167918D01*
G01X495378Y178639D02*
X493192Y168386D01*
G01X486296Y175234D02*
Y176088D01*
G01X487496Y175107D02*
Y176193D01*
G01Y175107D02*
Y176193D01*
G01X486296Y175234D02*
Y176088D01*
G01X480253Y166508D02*
X475185Y158705D01*
G01X478926Y162261D02*
X476313Y158238D01*
G01X481322Y165949D02*
X480397Y164525D01*
G01X481717Y169294D02*
X480257Y166509D01*
G01X482867Y168902D02*
X481320Y165953D01*
G01X482196Y172011D02*
X481717Y169294D01*
G01X483396Y171906D02*
X482867Y168902D01*
G01X482196Y176222D02*
Y172011D01*
G01X483396Y176463D02*
Y171906D01*
G01X478926Y162261D02*
X476313Y158238D01*
G01X480253Y166508D02*
X475185Y158705D01*
G01X481322Y165949D02*
X480397Y164525D01*
G01X480253Y166508D02*
X475185Y158705D01*
G01X482867Y168902D02*
X481320Y165953D01*
G01X481717Y169294D02*
X480257Y166509D01*
G01X483396Y171906D02*
X482867Y168902D01*
G01X482196Y172011D02*
X481717Y169294D01*
G01X483396Y176463D02*
Y171906D01*
G01X482196Y176222D02*
Y172011D01*
G01X478096Y171816D02*
Y176279D01*
G01X479296Y171710D02*
Y176385D01*
G01X477803Y170158D02*
X478096Y171816D01*
G01X478942Y169707D02*
X479296Y171710D01*
G01X476661Y168527D02*
X477803Y170158D01*
G01X477789Y168060D02*
X478942Y169707D01*
G01X471114Y159987D02*
X476661Y168527D01*
G01X472242Y159520D02*
X477789Y168060D01*
G01X471993Y158346D02*
X472242Y159520D01*
G01X479296Y171710D02*
Y176385D01*
G01X478096Y171816D02*
Y176279D01*
G01X478942Y169707D02*
X479296Y171710D01*
G01X477803Y170158D02*
X478096Y171816D01*
G01X477789Y168060D02*
X478942Y169707D01*
G01X476661Y168527D02*
X477803Y170158D01*
G01X472242Y159520D02*
X477789Y168060D01*
G01X471114Y159987D02*
X476661Y168527D01*
G01X471993Y158346D02*
X472242Y159520D01*
G01X474544Y170506D02*
X467566Y159758D01*
G01X473548Y171178D02*
X466438Y160225D01*
G01X475196Y171437D02*
X474544Y170506D01*
G01X473996Y171816D02*
X473548Y171178D01*
G01X475196Y176385D02*
Y171437D01*
G01X473996Y176279D02*
Y171816D01*
G01X473548Y171178D02*
X466438Y160225D01*
G01X474544Y170506D02*
X467566Y159758D01*
G01X473996Y171816D02*
X473548Y171178D01*
G01X475196Y171437D02*
X474544Y170506D01*
G01X473996Y176279D02*
Y171816D01*
G01X475196Y176385D02*
Y171437D01*
G01X467996Y172018D02*
X461840Y160688D01*
G01X469196Y171713D02*
X462978Y160268D01*
G01X467996Y176603D02*
Y172018D01*
G01X469196Y176959D02*
Y171713D01*
G01D02*
X462978Y160268D01*
G01X467996Y172018D02*
X461840Y160688D01*
G01X469196Y176959D02*
Y171713D01*
G01X467996Y176603D02*
Y172018D01*
G01X461574Y170543D02*
X455888Y161785D01*
G01X462569Y169871D02*
X457016Y161318D01*
G01X461835Y170915D02*
X461574Y170543D01*
G01X462971Y170444D02*
X462569Y169871D01*
G01X461915Y171369D02*
X461835Y170915D01*
G01X463196Y171720D02*
X462971Y170444D01*
G01X461940Y171513D02*
X461915Y171369D01*
G01X463196Y171720D02*
X462971Y170444D01*
G01X461996Y171825D02*
X461940Y171513D01*
G01X463196Y171720D02*
X462971Y170444D01*
G01X461996Y176542D02*
Y171825D01*
G01X463196Y176648D02*
Y171720D01*
G01X462569Y169871D02*
X457016Y161318D01*
G01X461574Y170543D02*
X455888Y161785D01*
G01X462971Y170444D02*
X462569Y169871D01*
G01X461835Y170915D02*
X461574Y170543D01*
G01X463196Y171720D02*
X462971Y170444D01*
G01X461915Y171369D02*
X461835Y170915D01*
G01X461940Y171513D02*
X461915Y171369D01*
G01X461996Y171825D02*
X461940Y171513D01*
G01X463196Y176648D02*
Y171720D01*
G01X461996Y176542D02*
Y171825D01*
G01X455846Y170644D02*
X450023Y162334D01*
G01X456982Y170173D02*
X451147Y161845D01*
G01X455996Y171492D02*
X455846Y170644D01*
G01X457196Y171387D02*
X456982Y170173D01*
G01X455996Y176875D02*
Y171492D01*
G01X457196Y176981D02*
Y171387D01*
G01X456982Y170173D02*
X451147Y161845D01*
G01X455846Y170644D02*
X450023Y162334D01*
G01X457196Y171387D02*
X456982Y170173D01*
G01X455996Y171492D02*
X455846Y170644D01*
G01X457196Y176981D02*
Y171387D01*
G01X455996Y176875D02*
Y171492D01*
G01X449996Y171463D02*
X449832Y170532D01*
G01X451196Y171358D02*
X450969Y170065D01*
G01X449996Y177038D02*
Y171463D01*
G01X451196Y177143D02*
Y171358D01*
G01D02*
X450969Y170065D01*
G01X449996Y171463D02*
X449832Y170532D01*
G01X451196Y177143D02*
Y171358D01*
G01X449996Y177038D02*
Y171463D01*
G01X509976Y198225D02*
X513378Y194823D01*
G01X510474Y199425D02*
X513976Y195924D01*
G01X509187Y198225D02*
X509976D01*
G01X510474Y199425D02*
X513976Y195924D01*
G01X509187Y199425D02*
X510474D01*
G01D02*
X513976Y195924D01*
G01X509976Y198225D02*
X513378Y194823D01*
G01X509187Y198225D02*
X509976D01*
G01X509187Y199425D02*
X510474D01*
G01X509187Y198225D02*
X509976D01*
G01X501375Y198442D02*
Y199382D01*
G01X502575D02*
Y198798D01*
G01X502774Y196286D02*
X501375Y198442D01*
G01X502575Y198798D02*
X503642Y197154D01*
G01X506728Y193718D02*
X502774Y196286D01*
G01X503642Y197154D02*
X507195Y194846D01*
G01X507815Y193487D02*
X506728Y193718D01*
G01X507195Y194846D02*
X508282Y194615D01*
G01X509637Y192305D02*
X507815Y193487D01*
G01X508282Y194615D02*
X512325Y191993D01*
G01X511457Y191125D02*
X509637Y192305D01*
G01X508282Y194615D02*
X512325Y191993D01*
G01X508282Y194615D02*
X512325Y191993D01*
G01X509637Y192305D02*
X507815Y193487D01*
G01X511457Y191125D02*
X509637Y192305D01*
G01X507195Y194846D02*
X508282Y194615D01*
G01X507815Y193487D02*
X506728Y193718D01*
G01X503642Y197154D02*
X507195Y194846D01*
G01X506728Y193718D02*
X502774Y196286D01*
G01X502575Y198798D02*
X503642Y197154D01*
G01X502774Y196286D02*
X501375Y198442D01*
G01X502575Y199382D02*
Y198798D01*
G01X501375Y198442D02*
Y199382D01*
G01X504031Y187142D02*
X505305Y181160D01*
G01X505159Y187610D02*
X506532Y181160D01*
G01X500485Y192603D02*
X504031Y187142D01*
G01X503466Y190217D02*
X505159Y187610D01*
G01X501342Y193488D02*
X501996Y192482D01*
G01X496204Y195190D02*
X500485Y192603D01*
G01X496655Y196320D02*
X501342Y193488D01*
G01X488459Y196835D02*
X496204Y195190D01*
G01X488459Y198062D02*
X496656Y196321D01*
G01X484867Y196071D02*
X488459Y196835D01*
G01X484868Y197299D02*
X488459Y198062D01*
G01X483325Y196401D02*
X484867Y196071D01*
G01X483792Y197529D02*
X484868Y197299D01*
G01X482319Y197052D02*
X483325Y196401D01*
G01X483187Y197921D02*
X483792Y197529D01*
G01X481874Y197739D02*
X482319Y197052D01*
G01X483002Y198206D02*
X483187Y197921D01*
G01X481690Y198609D02*
X481874Y197739D01*
G01X482890Y198735D02*
X483002Y198206D01*
G01X481690Y199260D02*
Y198609D01*
G01X482890Y199260D02*
Y198735D01*
G01X505159Y187610D02*
X506532Y181160D01*
G01X504031Y187142D02*
X505305Y181160D01*
G01X503466Y190217D02*
X505159Y187610D01*
G01X500485Y192603D02*
X504031Y187142D01*
G01X501342Y193488D02*
X501996Y192482D01*
G01X500485Y192603D02*
X504031Y187142D01*
G01X496655Y196320D02*
X501342Y193488D01*
G01X496204Y195190D02*
X500485Y192603D01*
G01X488459Y198062D02*
X496656Y196321D01*
G01X488459Y196835D02*
X496204Y195190D01*
G01X484868Y197299D02*
X488459Y198062D01*
G01X484867Y196071D02*
X488459Y196835D01*
G01X483792Y197529D02*
X484868Y197299D01*
G01X483325Y196401D02*
X484867Y196071D01*
G01X483187Y197921D02*
X483792Y197529D01*
G01X482319Y197052D02*
X483325Y196401D01*
G01X483002Y198206D02*
X483187Y197921D01*
G01X481874Y197739D02*
X482319Y197052D01*
G01X482890Y198735D02*
X483002Y198206D01*
G01X481690Y198609D02*
X481874Y197739D01*
G01X482890Y199260D02*
Y198735D01*
G01X481690Y199260D02*
Y198609D01*
G01X494253Y183970D02*
X495378Y178639D01*
G01X494296Y189584D02*
X496605Y178638D01*
G01X493632Y186914D02*
X494253Y183970D01*
G01X494296Y189584D02*
X496605Y178638D01*
G01X493128Y189303D02*
X493632Y186914D01*
G01X494296Y189584D02*
X496605Y178638D01*
G01X493015Y189697D02*
X493128Y189303D01*
G01X494120Y190200D02*
X494296Y189584D01*
G01X492529Y190444D02*
X493015Y189697D01*
G01X493397Y191313D02*
X494120Y190200D01*
G01X491316Y191231D02*
X492529Y190444D01*
G01X491783Y192359D02*
X493397Y191313D01*
G01X481430Y193332D02*
X491316Y191231D01*
G01X488679Y193019D02*
X491783Y192359D01*
G01X481897Y194460D02*
X486038Y193580D01*
G01X478852Y195005D02*
X481430Y193332D01*
G01X479720Y195873D02*
X481897Y194460D01*
G01X478072Y196207D02*
X478852Y195005D01*
G01X479201Y196674D02*
X479720Y195873D01*
G01X477762Y197668D02*
X478072Y196207D01*
G01X478962Y197794D02*
X479201Y196674D01*
G01X477762Y198982D02*
Y197668D01*
G01X478962Y198982D02*
Y197794D01*
G01X494296Y189584D02*
X496605Y178638D01*
G01X494253Y183970D02*
X495378Y178639D01*
G01X493632Y186914D02*
X494253Y183970D01*
G01X493128Y189303D02*
X493632Y186914D01*
G01X494120Y190200D02*
X494296Y189584D01*
G01X493015Y189697D02*
X493128Y189303D01*
G01X493397Y191313D02*
X494120Y190200D01*
G01X492529Y190444D02*
X493015Y189697D01*
G01X491783Y192359D02*
X493397Y191313D01*
G01X491316Y191231D02*
X492529Y190444D01*
G01X488679Y193019D02*
X491783Y192359D01*
G01X481430Y193332D02*
X491316Y191231D01*
G01X481897Y194460D02*
X486038Y193580D01*
G01X481430Y193332D02*
X491316Y191231D01*
G01X479720Y195873D02*
X481897Y194460D01*
G01X478852Y195005D02*
X481430Y193332D01*
G01X479201Y196674D02*
X479720Y195873D01*
G01X478072Y196207D02*
X478852Y195005D01*
G01X478962Y197794D02*
X479201Y196674D01*
G01X477762Y197668D02*
X478072Y196207D01*
G01X478962Y198982D02*
Y197794D01*
G01X477762Y198982D02*
Y197668D01*
G01X473808Y197055D02*
Y198913D01*
G01X475008Y197411D02*
Y198913D01*
G01X484809Y180112D02*
X473808Y197055D01*
G01X482671Y185610D02*
X475008Y197411D01*
G01X485805Y180784D02*
X484142Y183345D01*
G01X485847Y178635D02*
X484809Y180112D01*
G01X486983Y179107D02*
X485805Y180784D01*
G01X486296Y176088D02*
X485847Y178635D01*
G01X487496Y176193D02*
X486983Y179107D01*
G01X475008Y197411D02*
Y198913D01*
G01X473808Y197055D02*
Y198913D01*
G01X482671Y185610D02*
X475008Y197411D01*
G01X484809Y180112D02*
X473808Y197055D01*
G01X485805Y180784D02*
X484142Y183345D01*
G01X484809Y180112D02*
X473808Y197055D01*
G01X486983Y179107D02*
X485805Y180784D01*
G01X485847Y178635D02*
X484809Y180112D01*
G01X487496Y176193D02*
X486983Y179107D01*
G01X486296Y176088D02*
X485847Y178635D01*
G01X480220Y180964D02*
X482196Y176222D01*
G01X481823Y180239D02*
X483396Y176463D01*
G01X481287Y181526D02*
X481823Y180239D01*
G01X469888Y196871D02*
X480220Y180964D01*
G01X471088Y197227D02*
X481287Y181526D01*
G01X469888Y198982D02*
Y196871D01*
G01X471088Y198621D02*
Y197227D01*
G01X481823Y180239D02*
X483396Y176463D01*
G01X480220Y180964D02*
X482196Y176222D01*
G01X481287Y181526D02*
X481823Y180239D01*
G01X480220Y180964D02*
X482196Y176222D01*
G01X471088Y197227D02*
X481287Y181526D01*
G01X469888Y196871D02*
X480220Y180964D01*
G01X471088Y198621D02*
Y197227D01*
G01X469888Y198982D02*
Y196871D01*
G01X465934Y197605D02*
Y198913D01*
G01X467134Y197732D02*
Y198913D01*
G01X466271Y196021D02*
X465934Y197605D01*
G01X467399Y196489D02*
X467134Y197732D01*
G01X477725Y178384D02*
X466271Y196021D01*
G01X478865Y178833D02*
X467399Y196489D01*
G01X478096Y176279D02*
X477725Y178384D01*
G01X479296Y176385D02*
X478865Y178833D01*
G01X467134Y197732D02*
Y198913D01*
G01X465934Y197605D02*
Y198913D01*
G01X467399Y196489D02*
X467134Y197732D01*
G01X466271Y196021D02*
X465934Y197605D01*
G01X478865Y178833D02*
X467399Y196489D01*
G01X477725Y178384D02*
X466271Y196021D01*
G01X479296Y176385D02*
X478865Y178833D01*
G01X478096Y176279D02*
X477725Y178384D01*
G01X475018Y177397D02*
X475196Y176385D01*
G01X473938Y176604D02*
X473996Y176279D01*
G01X473881Y176927D02*
X473938Y176604D01*
G01X473120Y180112D02*
X475018Y177397D01*
G01X472257Y179250D02*
X473882Y176927D01*
G01X472061Y180853D02*
X473120Y180112D01*
G01X471216Y179979D02*
X472257Y179250D01*
G01X469637Y184585D02*
X472059Y180857D01*
G01X462868Y192801D02*
X471074Y180168D01*
G01X463996Y193268D02*
X468167Y186847D01*
G01X462868Y192801D02*
X471074Y180168D01*
G01X463214Y196963D02*
X463996Y193268D01*
G01X462014Y196837D02*
X462868Y192801D01*
G01X463214Y198982D02*
Y196963D01*
G01X462014Y198982D02*
Y196837D01*
G01X473938Y176604D02*
X473996Y176279D01*
G01X475018Y177397D02*
X475196Y176385D01*
G01X473881Y176927D02*
X473938Y176604D01*
G01X475018Y177397D02*
X475196Y176385D01*
G01X472257Y179250D02*
X473882Y176927D01*
G01X473120Y180112D02*
X475018Y177397D01*
G01X471216Y179979D02*
X472257Y179250D01*
G01X472061Y180853D02*
X473120Y180112D01*
G01X462868Y192801D02*
X471074Y180168D01*
G01X469637Y184585D02*
X472059Y180857D01*
G01X463996Y193268D02*
X468167Y186847D01*
G01X462014Y196837D02*
X462868Y192801D01*
G01X463214Y196963D02*
X463996Y193268D01*
G01X462014Y198982D02*
Y196837D01*
G01X463214Y198982D02*
Y196963D01*
G01X459716Y189358D02*
X467996Y176603D01*
G01X466824Y180612D02*
X469196Y176959D01*
G01X464646Y183969D02*
X466824Y180613D01*
G01X460844Y189825D02*
X463176Y186234D01*
G01X458060Y197147D02*
X459716Y189358D01*
G01X459260Y197274D02*
X460844Y189825D01*
G01X458060Y198913D02*
Y197147D01*
G01X459260Y198913D02*
Y197274D01*
G01X466824Y180612D02*
X469196Y176959D01*
G01X459716Y189358D02*
X467996Y176603D01*
G01X464646Y183969D02*
X466824Y180613D01*
G01X459716Y189358D02*
X467996Y176603D01*
G01X460844Y189825D02*
X463176Y186234D01*
G01X459716Y189358D02*
X467996Y176603D01*
G01X459260Y197274D02*
X460844Y189825D01*
G01X458060Y197147D02*
X459716Y189358D01*
G01X459260Y198913D02*
Y197274D01*
G01X458060Y198913D02*
Y197147D01*
G01X461784Y177741D02*
X461996Y176542D01*
G01X462710Y179406D02*
X463196Y176648D01*
G01X461582Y178888D02*
X461784Y177741D01*
G01X462710Y179406D02*
X463196Y176648D01*
G01X461574Y178936D02*
X461582Y178888D01*
G01X462710Y179406D02*
X463196Y176648D01*
G01X460875Y179934D02*
X461574Y178936D01*
G01X461871Y180606D02*
X462710Y179406D01*
G01X450223Y196333D02*
X460875Y179934D01*
G01X453547Y193418D02*
X461871Y180606D01*
G01X451423Y196690D02*
X452077Y195684D01*
G01X450223Y198982D02*
Y196333D01*
G01X451423Y198982D02*
Y196690D01*
G01X462710Y179406D02*
X463196Y176648D01*
G01X461784Y177741D02*
X461996Y176542D01*
G01X461582Y178888D02*
X461784Y177741D01*
G01X461574Y178936D02*
X461582Y178888D01*
G01X461871Y180606D02*
X462710Y179406D01*
G01X460875Y179934D02*
X461574Y178936D01*
G01X453547Y193418D02*
X461871Y180606D01*
G01X450223Y196333D02*
X460875Y179934D01*
G01X451423Y196690D02*
X452077Y195684D01*
G01X450223Y196333D02*
X460875Y179934D01*
G01X451423Y198982D02*
Y196690D01*
G01X450223Y198982D02*
Y196333D01*
G01X455681Y178661D02*
X455996Y176875D01*
G01X456861Y178883D02*
X457196Y176981D01*
G01X455579Y179172D02*
X455681Y178661D01*
G01X456861Y178883D02*
X457196Y176981D01*
G01X456711Y179633D02*
X456861Y178883D01*
G01X453289Y184902D02*
X456711Y179633D01*
G01X456861Y178883D02*
X457196Y176981D01*
G01X455681Y178661D02*
X455996Y176875D01*
G01X455579Y179172D02*
X455681Y178661D01*
G01X456711Y179633D02*
X456861Y178883D01*
G01X455579Y179172D02*
X455681Y178661D01*
G01X453289Y184902D02*
X456711Y179633D01*
G01X449601Y179279D02*
X449996Y177038D01*
G01X450737Y179749D02*
X451196Y177143D01*
G01X449106Y179986D02*
X449601Y179279D01*
G01X450102Y180658D02*
X450737Y179749D01*
G01D02*
X451196Y177143D01*
G01X449601Y179279D02*
X449996Y177038D01*
G01X450102Y180658D02*
X450737Y179749D01*
G01X449106Y179986D02*
X449601Y179279D01*
G01X473391Y413465D02*
X457854Y410162D01*
G01Y408935D02*
X473391Y412238D01*
G01X536441Y400063D02*
X473391Y413465D01*
G01Y412238D02*
X535974Y398935D01*
G01X473391Y412238D02*
X535974Y398935D01*
G01X536441Y400063D02*
X473391Y413465D01*
G01X457854Y408935D02*
X473391Y412238D01*
G01Y413465D02*
X457854Y410162D01*
G01X475468Y417692D02*
X458209Y414024D01*
G01X475468Y416465D02*
X458209Y412797D01*
G01X536723Y404672D02*
X475468Y417692D01*
G01X536256Y403544D02*
X475468Y416465D01*
G01D02*
X458209Y412797D01*
G01X475468Y417692D02*
X458209Y414024D01*
G01X536256Y403544D02*
X475468Y416465D01*
G01X536723Y404672D02*
X475468Y417692D01*
G01X535367Y390545D02*
X468267Y404808D01*
G01X534900Y389417D02*
X468267Y403581D01*
G01X534900Y389417D02*
X468267Y403581D01*
G01X535367Y390545D02*
X468267Y404808D01*
G01X471003Y409032D02*
X537486Y394902D01*
G01X537019Y393774D02*
X470754Y407858D01*
G01Y409085D02*
X471003Y409033D01*
G01X537019Y393774D02*
X470754Y407858D01*
G01X537019Y393774D02*
X470754Y407858D01*
G01X471003Y409032D02*
X537486Y394902D01*
G01X470754Y409085D02*
X471003Y409033D01*
G01X568298Y42800D02*
Y72714D01*
G01X569498Y42800D02*
Y72841D01*
G01X570359Y40739D02*
G02X568298Y42800I0J2061D01*
G01X570359Y41939D02*
G02X569498Y42800I0J861D01*
G01X571735Y40739D02*
X570359D01*
G01X571735Y41939D02*
X570359D01*
G01X569498Y42800D02*
Y72841D01*
G01X568298Y42800D02*
Y72714D01*
G01X570359Y41939D02*
G02X569498Y42800I0J861D01*
G01X570359Y40739D02*
G02X568298Y42800I0J2061D01*
G01X571735Y41939D02*
X570359D01*
G01X571735Y40739D02*
X570359D01*
G01X525778Y42801D02*
Y67281D01*
G01X526978Y67154D02*
Y42801D01*
G01X527840Y40739D02*
G02X525778Y42801I0J2062D01*
G01X526978D02*
G03X527840Y41939I862J0D01*
G01X529216Y40739D02*
X527840D01*
G01Y41939D02*
X529216D01*
G01X527840D02*
X529216D01*
G01Y40739D02*
X527840D01*
G01X526978Y42801D02*
G03X527840Y41939I862J0D01*
G01Y40739D02*
G02X525778Y42801I0J2062D01*
G01X526978Y67154D02*
Y42801D01*
G01X525778D02*
Y67281D01*
G01X556186Y40739D02*
X557562D01*
G01X556186Y41939D02*
X557562D01*
G01X554124Y42801D02*
G03X556186Y40739I2062J0D01*
G01X555324Y42801D02*
G03X556186Y41939I862J0D01*
G01X554124Y64707D02*
Y42801D01*
G01X555324Y64580D02*
Y42801D01*
G01X556186Y41939D02*
X557562D01*
G01X556186Y40739D02*
X557562D01*
G01X555324Y42801D02*
G03X556186Y41939I862J0D01*
G01X554124Y42801D02*
G03X556186Y40739I2062J0D01*
G01X555324Y64580D02*
Y42801D01*
G01X554124Y64707D02*
Y42801D01*
G01X513666Y41939D02*
X515042D01*
G01X513666Y40739D02*
X515042D01*
G01X512805Y42800D02*
G03X513666Y41939I861J0D01*
G01X511605Y42800D02*
G03X513666Y40739I2061J0D01*
G01X512805Y70802D02*
Y42800D01*
G01X511605Y58164D02*
Y42800D01*
G01X542013Y40739D02*
X543389D01*
G01X542013Y41939D02*
X543389D01*
G01X539951Y42801D02*
G03X542013Y40739I2062J0D01*
G01X541151Y42801D02*
G03X542013Y41939I862J0D01*
G01X539951Y59784D02*
Y42801D01*
G01X541151Y59657D02*
Y42801D01*
G01X542013Y41939D02*
X543389D01*
G01X542013Y40739D02*
X543389D01*
G01X541151Y42801D02*
G03X542013Y41939I862J0D01*
G01X539951Y42801D02*
G03X542013Y40739I2062J0D01*
G01X541151Y59657D02*
Y42801D01*
G01X539951Y59784D02*
Y42801D01*
G01X561212Y47524D02*
Y66980D01*
G01X562412Y66853D02*
Y47524D01*
G01X563273Y45463D02*
G02X561212Y47524I0J2061D01*
G01X562412D02*
G03X563273Y46663I861J0D01*
G01X564649Y45463D02*
X563273D01*
G01Y46663D02*
X564649D01*
G01X563273D02*
X564649D01*
G01Y45463D02*
X563273D01*
G01X562412Y47524D02*
G03X563273Y46663I861J0D01*
G01Y45463D02*
G02X561212Y47524I0J2061D01*
G01X562412Y66853D02*
Y47524D01*
G01X561212D02*
Y66980D01*
G01X520753Y45463D02*
X522129D01*
G01Y46663D02*
X520753D01*
G01X518692Y47524D02*
G03X520753Y45463I2061J0D01*
G01Y46663D02*
G02X519892Y47524I0J861D01*
G01X518692Y68382D02*
Y47524D01*
G01X519892D02*
Y68255D01*
G01Y47524D02*
Y68255D01*
G01X518692Y68382D02*
Y47524D01*
G01X520753Y46663D02*
G02X519892Y47524I0J861D01*
G01X518692D02*
G03X520753Y45463I2061J0D01*
G01X522129Y46663D02*
X520753D01*
G01Y45463D02*
X522129D01*
G01X549099D02*
X550475D01*
G01X549099Y46663D02*
X550475D01*
G01X547038Y47524D02*
G03X549099Y45463I2061J0D01*
G01X548238Y47524D02*
G03X549099Y46663I861J0D01*
G01X547038Y66066D02*
Y47524D01*
G01X548238Y65939D02*
Y47524D01*
G01X549099Y46663D02*
X550475D01*
G01X549099Y45463D02*
X550475D01*
G01X548238Y47524D02*
G03X549099Y46663I861J0D01*
G01X547038Y47524D02*
G03X549099Y45463I2061J0D01*
G01X548238Y65939D02*
Y47524D01*
G01X547038Y66066D02*
Y47524D01*
G01X534926Y45463D02*
X536302D01*
G01X534926Y46663D02*
X536302D01*
G01X532865Y47524D02*
G03X534926Y45463I2061J0D01*
G01X534065Y47524D02*
G03X534926Y46663I861J0D01*
G01X532865Y63557D02*
Y47524D01*
G01X534065Y63430D02*
Y47524D01*
G01X534926Y46663D02*
X536302D01*
G01X534926Y45463D02*
X536302D01*
G01X534065Y47524D02*
G03X534926Y46663I861J0D01*
G01X532865Y47524D02*
G03X534926Y45463I2061J0D01*
G01X534065Y63430D02*
Y47524D01*
G01X532865Y63557D02*
Y47524D01*
G01X513666Y40739D02*
X515042D01*
G01X513666Y41939D02*
X515042D01*
G01X511605Y42800D02*
G03X513666Y40739I2061J0D01*
G01X512805Y42800D02*
G03X513666Y41939I861J0D01*
G01X511605Y58164D02*
Y42800D01*
G01X512805Y70802D02*
Y42800D01*
G01Y70802D02*
Y42800D01*
G01Y70802D02*
Y42800D01*
G01X566617Y127711D02*
X582471Y53123D01*
G01X567844Y127711D02*
X583671Y53250D01*
G01X567844Y127711D02*
X583671Y53250D01*
G01X566617Y127711D02*
X582471Y53123D01*
G01X568298Y72714D02*
X557273Y124587D01*
G01X569498Y72841D02*
X558500Y124587D01*
G01X569498Y72841D02*
X558500Y124587D01*
G01X568298Y72714D02*
X557273Y124587D01*
G01X532019Y96632D02*
X528195Y114621D01*
G01X529422D02*
X533246Y96632D01*
G01X528898Y81955D02*
X532019Y96632D01*
G01X533246D02*
X526978Y67154D01*
G01X525778Y67281D02*
X528897Y81955D01*
G01X533246Y96632D02*
X526978Y67154D01*
G01X533246Y96632D02*
X526978Y67154D01*
G01X528898Y81955D02*
X532019Y96632D01*
G01X525778Y67281D02*
X528897Y81955D01*
G01X529422Y114621D02*
X533246Y96632D01*
G01X532019D02*
X528195Y114621D01*
G01X556865Y77606D02*
X554124Y64707D01*
G01X558092Y77606D02*
X555324Y64580D01*
G01X547607Y121181D02*
X556865Y77606D01*
G01X548834Y121181D02*
X558092Y77606D01*
G01D02*
X555324Y64580D01*
G01X556865Y77606D02*
X554124Y64707D01*
G01X548834Y121181D02*
X558092Y77606D01*
G01X547607Y121181D02*
X556865Y77606D01*
G01X511605Y62064D02*
Y60864D01*
G01Y70929D02*
Y64764D01*
G01X535249Y176411D02*
X512805Y70802D01*
G01X534022Y176411D02*
X511605Y70929D01*
G01X545104Y84027D02*
X539951Y59784D01*
G01X546331Y84027D02*
X541151Y59657D01*
G01X538056Y117192D02*
X545104Y84027D01*
G01X539283Y117192D02*
X546331Y84027D01*
G01D02*
X541151Y59657D01*
G01X545104Y84027D02*
X539951Y59784D01*
G01X539283Y117192D02*
X546331Y84027D01*
G01X538056Y117192D02*
X545104Y84027D01*
G01X561904Y125686D02*
X575385Y62266D01*
G01X563131Y125686D02*
X576585Y62393D01*
G01X563131Y125686D02*
X576585Y62393D01*
G01X561904Y125686D02*
X575385Y62266D01*
G01X562687Y73919D02*
X551906Y124651D01*
G01X553133D02*
X563914Y73919D01*
G01X561212Y66980D02*
X562687Y73919D01*
G01X563914D02*
X562412Y66853D01*
G01X563914Y73919D02*
X562412Y66853D01*
G01X561212Y66980D02*
X562687Y73919D01*
G01X553133Y124651D02*
X563914Y73919D01*
G01X562687D02*
X551906Y124651D01*
G01X525254Y99252D02*
X518692Y68382D01*
G01X519892Y68255D02*
X526481Y99252D01*
G01X523281Y108533D02*
X525254Y99252D01*
G01X526481D02*
X524508Y108533D01*
G01X537908Y177352D02*
X523281Y108533D01*
G01X524508D02*
X539135Y177352D01*
G01X524508Y108533D02*
X539135Y177352D01*
G01X537908D02*
X523281Y108533D01*
G01X526481Y99252D02*
X524508Y108533D01*
G01X523281D02*
X525254Y99252D01*
G01X519892Y68255D02*
X526481Y99252D01*
G01X525254D02*
X518692Y68382D01*
G01X550536Y82529D02*
X547038Y66066D01*
G01X551763Y82529D02*
X548238Y65939D01*
G01X542309Y121248D02*
X550536Y82529D01*
G01X543536Y121248D02*
X551763Y82529D01*
G01D02*
X548238Y65939D01*
G01X550536Y82529D02*
X547038Y66066D01*
G01X543536Y121248D02*
X551763Y82529D01*
G01X542309Y121248D02*
X550536Y82529D01*
G01X538764Y91305D02*
X532865Y63557D01*
G01X539991Y91305D02*
X534065Y63430D01*
G01X533287Y117079D02*
X538764Y91305D01*
G01X534514Y117079D02*
X539991Y91305D01*
G01D02*
X534065Y63430D01*
G01X538764Y91305D02*
X532865Y63557D01*
G01X534514Y117079D02*
X539991Y91305D01*
G01X533287Y117079D02*
X538764Y91305D01*
G01X511605Y62064D02*
Y60864D01*
G01Y70929D02*
Y64764D01*
G01X534022Y176411D02*
X511605Y70929D01*
G01X535249Y176411D02*
X512805Y70802D01*
G01X575765Y170752D02*
X566617Y127711D01*
G01X576992Y170752D02*
X567844Y127711D01*
G01X576992Y170752D02*
X567844Y127711D01*
G01X575765Y170752D02*
X566617Y127711D01*
G01X567242Y171488D02*
X561236Y199742D01*
G01X568469Y171488D02*
X562463Y199742D01*
G01X557273Y124587D02*
X567242Y171488D01*
G01X558500Y124587D02*
X568469Y171488D01*
G01D02*
X562463Y199742D01*
G01X567242Y171488D02*
X561236Y199742D01*
G01X558500Y124587D02*
X568469Y171488D01*
G01X557273Y124587D02*
X567242Y171488D01*
G01X528195Y114621D02*
X541672Y178048D01*
G01X542899D02*
X529422Y114621D01*
G01X542899Y178048D02*
X529422Y114621D01*
G01X528195D02*
X541672Y178048D01*
G01X558808Y173884D02*
X547607Y121181D01*
G01X560035Y173884D02*
X548834Y121181D01*
G01X549564Y217371D02*
X558808Y173884D01*
G01X550692Y217838D02*
X560035Y173884D01*
G01D02*
X548834Y121181D01*
G01X558808Y173884D02*
X547607Y121181D01*
G01X550692Y217838D02*
X560035Y173884D01*
G01X549564Y217371D02*
X558808Y173884D01*
G01X550314Y174884D02*
X538056Y117192D01*
G01X551541Y174884D02*
X539283Y117192D01*
G01X542456Y211863D02*
X550314Y174884D01*
G01X543584Y212330D02*
X551541Y174884D01*
G01D02*
X539283Y117192D01*
G01X550314Y174884D02*
X538056Y117192D01*
G01X543584Y212330D02*
X551541Y174884D01*
G01X542456Y211863D02*
X550314Y174884D01*
G01X571615Y171366D02*
X561904Y125686D01*
G01X572842Y171366D02*
X563131Y125686D01*
G01X565820Y198614D02*
X571615Y171366D01*
G01X567047Y198614D02*
X572842Y171366D01*
G01D02*
X563131Y125686D01*
G01X571615Y171366D02*
X561904Y125686D01*
G01X567047Y198614D02*
X572842Y171366D01*
G01X565820Y198614D02*
X571615Y171366D01*
G01X562687Y175372D02*
X556997Y202139D01*
G01X558224Y202143D02*
X563914Y175372D01*
G01X551906Y124651D02*
X562687Y175372D01*
G01X563914D02*
X553133Y124651D01*
G01X563914Y175372D02*
X553133Y124651D01*
G01X551906D02*
X562687Y175372D01*
G01X558224Y202143D02*
X563914Y175372D01*
G01X562687D02*
X556997Y202139D01*
G01X554202Y177197D02*
X542309Y121248D01*
G01X555429Y177197D02*
X543536Y121248D01*
G01X555429Y177197D02*
X543536Y121248D01*
G01X554202Y177197D02*
X542309Y121248D01*
G01X545932Y176578D02*
X533287Y117079D01*
G01X547159Y176578D02*
X534514Y117079D01*
G01X547159Y176578D02*
X534514Y117079D01*
G01X545932Y176578D02*
X533287Y117079D01*
G01X570274Y196588D02*
X575765Y170752D01*
G01X571501Y196588D02*
X576992Y170752D01*
G01X579329Y239184D02*
X570274Y196588D01*
G01X580556Y239184D02*
X571501Y196588D01*
G01D02*
X576992Y170752D01*
G01X570274Y196588D02*
X575765Y170752D01*
G01X580556Y239184D02*
X571501Y196588D01*
G01X579329Y239184D02*
X570274Y196588D01*
G01X561236Y199742D02*
X569452Y238398D01*
G01X562463Y199742D02*
X570679Y238398D01*
G01X562463Y199742D02*
X570679Y238398D01*
G01X561236Y199742D02*
X569452Y238398D01*
G01X523838Y218173D02*
Y247111D01*
G01X525038Y247609D02*
Y218300D01*
G01X524792Y213687D02*
X523838Y218173D01*
G01X525038Y218300D02*
X525920Y214154D01*
G01X529552Y206354D02*
X524792Y213687D01*
G01X525920Y214154D02*
X529257Y209013D01*
G01X531675Y203084D02*
X531022Y204090D01*
G01X529257Y209013D02*
X539753Y192850D01*
G01X538626Y192379D02*
X533146Y200819D01*
G01X529257Y209013D02*
X539753Y192850D01*
G01X541672Y178048D02*
X538626Y192379D01*
G01X539753Y192850D02*
X542899Y178048D01*
G01X539753Y192850D02*
X542899Y178048D01*
G01X541672D02*
X538626Y192379D01*
G01X529257Y209013D02*
X539753Y192850D01*
G01X531675Y203084D02*
X531022Y204090D01*
G01X538626Y192379D02*
X533146Y200819D01*
G01X525920Y214154D02*
X529257Y209013D01*
G01X529552Y206354D02*
X524792Y213687D01*
G01X525038Y218300D02*
X525920Y214154D01*
G01X524792Y213687D02*
X523838Y218173D01*
G01X525038Y247609D02*
Y218300D01*
G01X523838Y218173D02*
Y247111D01*
G01X544631Y224972D02*
X549564Y217371D01*
G01X542047Y231162D02*
X550692Y217838D01*
G01X542508Y228243D02*
X543162Y227237D01*
G01X542047Y231162D02*
X550692Y217838D01*
G01X539689Y232588D02*
X541039Y230508D01*
G01X541433Y232107D02*
X542046Y231161D01*
G01X540817Y233055D02*
X541432Y232107D01*
G01X539081Y235448D02*
X539689Y232588D01*
G01X540281Y235575D02*
X540817Y233055D01*
G01X539081Y254221D02*
Y235448D01*
G01X540281Y254719D02*
Y235575D01*
G01X542047Y231162D02*
X550692Y217838D01*
G01X544631Y224972D02*
X549564Y217371D01*
G01X542508Y228243D02*
X543162Y227237D01*
G01X541433Y232107D02*
X542046Y231161D01*
G01X539689Y232588D02*
X541039Y230508D01*
G01X540817Y233055D02*
X541432Y232107D01*
G01X539689Y232588D02*
X541039Y230508D01*
G01X540281Y235575D02*
X540817Y233055D01*
G01X539081Y235448D02*
X539689Y232588D01*
G01X540281Y254719D02*
Y235575D01*
G01X539081Y254221D02*
Y235448D01*
G01X532318Y190205D02*
X535249Y176411D01*
G01X531190Y189738D02*
X534022Y176411D01*
G01X521576Y206746D02*
X532318Y190205D01*
G01X520448Y206279D02*
X531190Y189738D01*
G01X519900Y214629D02*
X521576Y206746D01*
G01X518700Y214502D02*
X520448Y206279D01*
G01X519900Y245271D02*
Y214629D01*
G01X518700Y244773D02*
Y214502D01*
G01X539677Y216140D02*
X542456Y211863D01*
G01X535872Y224202D02*
X543584Y212330D01*
G01X537553Y219410D02*
X538207Y218404D01*
G01X535872Y224202D02*
X543584Y212330D01*
G01X534719Y223773D02*
X536082Y221675D01*
G01X535872Y224202D02*
X543584Y212330D01*
G01X533747Y230858D02*
X534719Y223773D01*
G01X535248Y228747D02*
X535872Y224202D01*
G01X533424Y233212D02*
X533747Y230858D01*
G01X534624Y233294D02*
X535248Y228747D01*
G01X533424Y233822D02*
Y233212D01*
G01X534624Y234320D02*
Y233294D01*
G01X529420Y237826D02*
X533424Y233822D01*
G01X530620Y238324D02*
X534624Y234320D01*
G01X535872Y224202D02*
X543584Y212330D01*
G01X539677Y216140D02*
X542456Y211863D01*
G01X537553Y219410D02*
X538207Y218404D01*
G01X534719Y223773D02*
X536082Y221675D01*
G01X535248Y228747D02*
X535872Y224202D01*
G01X533747Y230858D02*
X534719Y223773D01*
G01X534624Y233294D02*
X535248Y228747D01*
G01X533424Y233212D02*
X533747Y230858D01*
G01X534624Y234320D02*
Y233294D01*
G01X533424Y233822D02*
Y233212D01*
G01X530620Y238324D02*
X534624Y234320D01*
G01X529420Y237826D02*
X533424Y233822D01*
G01X574338Y238679D02*
X565820Y198614D01*
G01X575565Y238679D02*
X567047Y198614D01*
G01X575565Y238679D02*
X567047Y198614D01*
G01X574338Y238679D02*
X565820Y198614D01*
G01X556997Y202139D02*
X564997Y240958D01*
G01X566224Y240962D02*
X558224Y202143D01*
G01X566224Y240962D02*
X558224Y202143D01*
G01X556997Y202139D02*
X564997Y240958D01*
G01X535122Y190458D02*
X537908Y177352D01*
G01X539135D02*
X536250Y190925D01*
G01X528160Y201179D02*
X535122Y190458D01*
G01X536250Y190925D02*
X526125Y206517D01*
G01X526036Y204449D02*
X526689Y203443D01*
G01X536250Y190925D02*
X526125Y206517D01*
G01X523156Y208885D02*
X524565Y206714D01*
G01X526124Y206518D02*
X524284Y209352D01*
G01X521300Y217615D02*
X523156Y208885D01*
G01X524284Y209352D02*
X522500Y217742D01*
G01X521300Y245975D02*
Y217615D01*
G01X522500Y217742D02*
Y246473D01*
G01Y217742D02*
Y246473D01*
G01X521300Y245975D02*
Y217615D01*
G01X524284Y209352D02*
X522500Y217742D01*
G01X521300Y217615D02*
X523156Y208885D01*
G01X526124Y206518D02*
X524284Y209352D01*
G01X523156Y208885D02*
X524565Y206714D01*
G01X536250Y190925D02*
X526125Y206517D01*
G01X528160Y201179D02*
X535122Y190458D01*
G01X526036Y204449D02*
X526689Y203443D01*
G01X539135Y177352D02*
X536250Y190925D01*
G01X535122Y190458D02*
X537908Y177352D01*
G01X546316Y214296D02*
X554202Y177197D01*
G01X551433Y195996D02*
X555429Y177197D01*
G01X549462Y205270D02*
X551433Y195996D01*
G01X547444Y214763D02*
X549462Y205270D01*
G01X537450Y227945D02*
X546316Y214296D01*
G01X538578Y228412D02*
X547444Y214763D01*
G01X536242Y233627D02*
X537450Y227945D01*
G01X537442Y233754D02*
X538578Y228412D01*
G01X536242Y252858D02*
Y233627D01*
G01X537442Y253356D02*
Y233754D01*
G01X551433Y195996D02*
X555429Y177197D01*
G01X546316Y214296D02*
X554202Y177197D01*
G01X549462Y205270D02*
X551433Y195996D01*
G01X546316Y214296D02*
X554202Y177197D01*
G01X547444Y214763D02*
X549462Y205270D01*
G01X546316Y214296D02*
X554202Y177197D01*
G01X538578Y228412D02*
X547444Y214763D01*
G01X537450Y227945D02*
X546316Y214296D01*
G01X537442Y233754D02*
X538578Y228412D01*
G01X536242Y233627D02*
X537450Y227945D01*
G01X537442Y253356D02*
Y233754D01*
G01X536242Y252858D02*
Y233627D01*
G01X542285Y193733D02*
X545932Y176578D01*
G01X543412Y194207D02*
X547159Y176578D01*
G01X535991Y203429D02*
X542285Y193733D01*
G01X527714Y218382D02*
X543412Y194207D01*
G01X533868Y206700D02*
X534521Y205693D01*
G01X527714Y218382D02*
X543412Y194207D01*
G01X526514Y218026D02*
X532397Y208964D01*
G01X527714Y218382D02*
X543412Y194207D01*
G01X526514Y248014D02*
Y218026D01*
G01X527714Y248512D02*
Y218382D01*
G01X543412Y194207D02*
X547159Y176578D01*
G01X542285Y193733D02*
X545932Y176578D01*
G01X527714Y218382D02*
X543412Y194207D01*
G01X535991Y203429D02*
X542285Y193733D01*
G01X533868Y206700D02*
X534521Y205693D01*
G01X526514Y218026D02*
X532397Y208964D01*
G01X527714Y248512D02*
Y218382D01*
G01X526514Y248014D02*
Y218026D01*
G01X531190Y189738D02*
X534022Y176411D01*
G01X532318Y190205D02*
X535249Y176411D01*
G01X520448Y206279D02*
X531190Y189738D01*
G01X521576Y206746D02*
X532318Y190205D01*
G01X518700Y214502D02*
X520448Y206279D01*
G01X519900Y214629D02*
X521576Y206746D01*
G01X518700Y244773D02*
Y214502D01*
G01X519900Y245271D02*
Y214629D01*
G01X522528Y189637D02*
X523820Y183556D01*
G01X523656Y190104D02*
X525047Y183556D01*
G01X521700Y190911D02*
X522528Y189637D01*
G01X522568Y191779D02*
X523656Y190104D01*
G01X516794Y194098D02*
X521700Y190911D01*
G01X517261Y195226D02*
X522568Y191779D01*
G01X513378Y194823D02*
X516794Y194098D01*
G01X513976Y195924D02*
X517261Y195226D01*
G01X523656Y190104D02*
X525047Y183556D01*
G01X522528Y189637D02*
X523820Y183556D01*
G01X522568Y191779D02*
X523656Y190104D01*
G01X521700Y190911D02*
X522528Y189637D01*
G01X517261Y195226D02*
X522568Y191779D01*
G01X516794Y194098D02*
X521700Y190911D01*
G01X513976Y195924D02*
X517261Y195226D01*
G01X513378Y194823D02*
X516794Y194098D01*
G01X511935Y190390D02*
X511457Y191125D01*
G01X512325Y191993D02*
X513538Y190123D01*
G01X512410Y189657D02*
X511935Y190390D01*
G01X512325Y191993D02*
X513538Y190123D01*
G01X513780Y183215D02*
X512410Y189657D01*
G01X513538Y190123D02*
X515006Y183223D01*
G01X513232Y180472D02*
X513780Y183215D01*
G01X515006Y183223D02*
X514505Y180716D01*
G01X515006Y183223D02*
X514505Y180716D01*
G01X513232Y180472D02*
X513780Y183215D01*
G01X513538Y190123D02*
X515006Y183223D01*
G01X513780Y183215D02*
X512410Y189657D01*
G01X512325Y191993D02*
X513538Y190123D01*
G01X511935Y190390D02*
X511457Y191125D01*
G01X512410Y189657D02*
X511935Y190390D01*
G01X513258Y217217D02*
Y237198D01*
G01X514458D02*
Y217344D01*
G01X515329Y207468D02*
X513258Y217217D01*
G01X514458Y217344D02*
X516457Y207935D01*
G01X516084Y206305D02*
X515329Y207468D01*
G01X516457Y207935D02*
X528191Y189868D01*
G01X527063Y189401D02*
X517555Y204040D01*
G01X516457Y207935D02*
X528191Y189868D01*
G01X529513Y177871D02*
X527063Y189401D01*
G01X528191Y189868D02*
X530740Y177871D01*
G01X528191Y189868D02*
X530740Y177871D01*
G01X529513D02*
X527063Y189401D01*
G01X516457Y207935D02*
X528191Y189868D01*
G01X516084Y206305D02*
X515329Y207468D01*
G01X527063Y189401D02*
X517555Y204040D01*
G01X514458Y217344D02*
X516457Y207935D01*
G01X515329Y207468D02*
X513258Y217217D01*
G01X514458Y237198D02*
Y217344D01*
G01X513258Y217217D02*
Y237198D01*
G01X568081Y269566D02*
X575205Y258599D01*
G01X568949Y270434D02*
X576333Y259066D01*
G01X563245Y272705D02*
X568081Y269566D01*
G01X548051Y284000D02*
X568949Y270434D01*
G01X559974Y274828D02*
X560981Y274175D01*
G01X548051Y284000D02*
X568949Y270434D01*
G01X556703Y276952D02*
X557710Y276299D01*
G01X548051Y284000D02*
X568949Y270434D01*
G01X547695Y282800D02*
X554439Y278422D01*
G01X548051Y284000D02*
X568949Y270434D01*
G01X529383Y282800D02*
X547695D01*
G01X529881Y284000D02*
X548051D01*
G01X520883Y291300D02*
X529383Y282800D01*
G01X521381Y292500D02*
X529881Y284000D01*
G01X515100Y291300D02*
X520883D01*
G01X514602Y292500D02*
X521381D01*
G01X514454Y290654D02*
X515100Y291300D01*
G01X513254Y291152D02*
X514602Y292500D01*
G01X514454Y289787D02*
Y290654D01*
G01X513254Y289787D02*
Y291152D01*
G01X568949Y270434D02*
X576333Y259066D01*
G01X568081Y269566D02*
X575205Y258599D01*
G01X548051Y284000D02*
X568949Y270434D01*
G01X563245Y272705D02*
X568081Y269566D01*
G01X559974Y274828D02*
X560981Y274175D01*
G01X556703Y276952D02*
X557710Y276299D01*
G01X547695Y282800D02*
X554439Y278422D01*
G01X529881Y284000D02*
X548051D01*
G01X529383Y282800D02*
X547695D01*
G01X521381Y292500D02*
X529881Y284000D01*
G01X520883Y291300D02*
X529383Y282800D01*
G01X514602Y292500D02*
X521381D01*
G01X515100Y291300D02*
X520883D01*
G01X513254Y291152D02*
X514602Y292500D01*
G01X514454Y290654D02*
X515100Y291300D01*
G01X513254Y289787D02*
Y291152D01*
G01X514454Y289787D02*
Y290654D01*
G01X519717Y280903D02*
X517559D01*
G01X520215Y282103D02*
X517198D01*
G01X530220Y270400D02*
X519717Y280903D01*
G01X530718Y271600D02*
X520215Y282103D01*
G01X546069Y270400D02*
X530220D01*
G01X546425Y271600D02*
X530718D01*
G01X547160Y269692D02*
X546069Y270400D01*
G01X552932Y267376D02*
X546425Y271600D01*
G01X550430Y267569D02*
X549424Y268222D01*
G01X552932Y267376D02*
X546425Y271600D01*
G01X562725Y259587D02*
X552695Y266098D01*
G01X563593Y260455D02*
X552932Y267375D01*
G01X566033Y254492D02*
X562725Y259587D01*
G01X567161Y254959D02*
X563593Y260455D01*
G01X569452Y238398D02*
X566033Y254492D01*
G01X570679Y238398D02*
X567161Y254959D01*
G01X520215Y282103D02*
X517198D01*
G01X519717Y280903D02*
X517559D01*
G01X530718Y271600D02*
X520215Y282103D01*
G01X530220Y270400D02*
X519717Y280903D01*
G01X546425Y271600D02*
X530718D01*
G01X546069Y270400D02*
X530220D01*
G01X552932Y267376D02*
X546425Y271600D01*
G01X547160Y269692D02*
X546069Y270400D01*
G01X550430Y267569D02*
X549424Y268222D01*
G01X563593Y260455D02*
X552932Y267375D01*
G01X562725Y259587D02*
X552695Y266098D01*
G01X567161Y254959D02*
X563593Y260455D01*
G01X566033Y254492D02*
X562725Y259587D01*
G01X570679Y238398D02*
X567161Y254959D01*
G01X569452Y238398D02*
X566033Y254492D01*
G01X518465Y253335D02*
X518065D01*
G01X518963Y254535D02*
X521422Y252076D01*
G01X518065Y254535D02*
X518963D01*
G01X520222Y251578D02*
X518465Y253335D01*
G01X518963Y254535D02*
X521422Y252076D01*
G01X520222Y250727D02*
Y251578D01*
G01X521422Y252076D02*
Y251225D01*
G01X523838Y247111D02*
X520222Y250727D01*
G01X521422Y251225D02*
X525038Y247609D01*
G01X521422Y251225D02*
X525038Y247609D01*
G01X523838Y247111D02*
X520222Y250727D01*
G01X521422Y252076D02*
Y251225D01*
G01X520222Y250727D02*
Y251578D01*
G01X518963Y254535D02*
X521422Y252076D01*
G01X518465Y253335D02*
X518065D01*
G01X520222Y251578D02*
X518465Y253335D01*
G01X518065Y254535D02*
X518963D01*
G01X518465Y253335D02*
X518065D01*
G01X532302Y261000D02*
X539081Y254221D01*
G01X532800Y262200D02*
X540281Y254719D01*
G01X530302Y261000D02*
X532302D01*
G01X530800Y262200D02*
X532800D01*
G01X518207Y273095D02*
X530302Y261000D01*
G01X530800Y262200D02*
X532800D01*
G01X518705Y274295D02*
X530800Y262200D01*
G01X517464Y273095D02*
X518207D01*
G01X517464Y274295D02*
X518705D01*
G01X532800Y262200D02*
X540281Y254719D01*
G01X532302Y261000D02*
X539081Y254221D01*
G01X530800Y262200D02*
X532800D01*
G01X530302Y261000D02*
X532302D01*
G01X518207Y273095D02*
X530302Y261000D01*
G01X518705Y274295D02*
X530800Y262200D01*
G01X518207Y273095D02*
X530302Y261000D01*
G01X517464Y274295D02*
X518705D01*
G01X517464Y273095D02*
X518207D01*
G01X518506Y246665D02*
X519900Y245271D01*
G01X518008Y245465D02*
X518700Y244773D01*
G01X517608Y246665D02*
X518506D01*
G01X517608Y245465D02*
X518008D01*
G01X529420Y249070D02*
Y237826D01*
G01X530620Y249568D02*
Y238324D01*
G01X525801Y252689D02*
X529420Y249070D01*
G01X527001Y253187D02*
X530620Y249568D01*
G01X525801Y255072D02*
Y252689D01*
G01X527001Y255570D02*
Y253187D01*
G01X518773Y262100D02*
X525801Y255072D01*
G01X519271Y263300D02*
X527001Y255570D01*
G01X516209Y262100D02*
X518773D01*
G01X516209Y263300D02*
X519271D01*
G01X530620Y249568D02*
Y238324D01*
G01X529420Y249070D02*
Y237826D01*
G01X527001Y253187D02*
X530620Y249568D01*
G01X525801Y252689D02*
X529420Y249070D01*
G01X527001Y255570D02*
Y253187D01*
G01X525801Y255072D02*
Y252689D01*
G01X519271Y263300D02*
X527001Y255570D01*
G01X518773Y262100D02*
X525801Y255072D01*
G01X516209Y263300D02*
X519271D01*
G01X516209Y262100D02*
X518773D01*
G01X570721Y255703D02*
X574338Y238679D01*
G01X571849Y256170D02*
X575565Y238679D01*
G01X564856Y264733D02*
X570721Y255703D01*
G01X565724Y265601D02*
X571849Y256170D01*
G01X558779Y268680D02*
X564856Y264733D01*
G01X547251Y277600D02*
X565724Y265601D01*
G01X555509Y270805D02*
X556515Y270151D01*
G01X547251Y277600D02*
X565724Y265601D01*
G01X546895Y276400D02*
X553244Y272275D01*
G01X547251Y277600D02*
X565724Y265601D01*
G01X529558Y276400D02*
X546895D01*
G01X530056Y277600D02*
X547251D01*
G01X521130Y284828D02*
X529558Y276400D01*
G01X521628Y286028D02*
X530056Y277600D01*
G01X517500Y284828D02*
X521130D01*
G01X517139Y286028D02*
X521628D01*
G01X571849Y256170D02*
X575565Y238679D01*
G01X570721Y255703D02*
X574338Y238679D01*
G01X565724Y265601D02*
X571849Y256170D01*
G01X564856Y264733D02*
X570721Y255703D01*
G01X547251Y277600D02*
X565724Y265601D01*
G01X558779Y268680D02*
X564856Y264733D01*
G01X555509Y270805D02*
X556515Y270151D01*
G01X546895Y276400D02*
X553244Y272275D01*
G01X530056Y277600D02*
X547251D01*
G01X529558Y276400D02*
X546895D01*
G01X521628Y286028D02*
X530056Y277600D01*
G01X521130Y284828D02*
X529558Y276400D01*
G01X517139Y286028D02*
X521628D01*
G01X517500Y284828D02*
X521130D01*
G01X519599Y276957D02*
X517193D01*
G01X517554Y278157D02*
X520097D01*
G01X532056Y264500D02*
X519599Y276957D01*
G01X520097Y278157D02*
X532554Y265700D01*
G01X545908Y264500D02*
X532056D01*
G01X532554Y265700D02*
X546264D01*
G01X550477Y261534D02*
X545908Y264500D01*
G01X546264Y265700D02*
X560771Y256284D01*
G01X553748Y259411D02*
X552741Y260064D01*
G01X546264Y265700D02*
X560771Y256284D01*
G01X559903Y255416D02*
X556013Y257941D01*
G01X546264Y265700D02*
X560771Y256284D01*
G01X562909Y250785D02*
X559903Y255416D01*
G01X560771Y256284D02*
X564037Y251252D01*
G01X564997Y240958D02*
X562909Y250785D01*
G01X564037Y251252D02*
X566224Y240962D01*
G01X564037Y251252D02*
X566224Y240962D01*
G01X564997Y240958D02*
X562909Y250785D01*
G01X560771Y256284D02*
X564037Y251252D01*
G01X562909Y250785D02*
X559903Y255416D01*
G01X546264Y265700D02*
X560771Y256284D01*
G01X550477Y261534D02*
X545908Y264500D01*
G01X553748Y259411D02*
X552741Y260064D01*
G01X559903Y255416D02*
X556013Y257941D01*
G01X532554Y265700D02*
X546264D01*
G01X545908Y264500D02*
X532056D01*
G01X520097Y278157D02*
X532554Y265700D01*
G01X532056Y264500D02*
X519599Y276957D01*
G01X517554Y278157D02*
X520097D01*
G01X519599Y276957D02*
X517193D01*
G01X517880Y249395D02*
X521300Y245975D01*
G01X522500Y246473D02*
X518378Y250595D01*
G01X517121Y249395D02*
X517880D01*
G01X518378Y250595D02*
X517121D01*
G01X522500Y246473D02*
X518378Y250595D01*
G01D02*
X517121D01*
G01Y249395D02*
X517880D01*
G01X522500Y246473D02*
X518378Y250595D01*
G01X517880Y249395D02*
X521300Y245975D01*
G01X517121Y249395D02*
X517880D01*
G01X531600Y257500D02*
X536242Y252858D01*
G01X532098Y258700D02*
X537442Y253356D01*
G01X528802Y257500D02*
X531600D01*
G01X529300Y258700D02*
X532098D01*
G01X522732Y263570D02*
X528802Y257500D01*
G01X517715Y270285D02*
X529300Y258700D01*
G01X521672Y263570D02*
X522732D01*
G01X517715Y270285D02*
X529300Y258700D01*
G01X519975Y266327D02*
X520823Y265479D01*
G01X517715Y270285D02*
X529300Y258700D01*
G01X518914Y266327D02*
X519975D01*
G01X517715Y270285D02*
X529300Y258700D01*
G01X517217Y269085D02*
X518066Y268236D01*
G01X517715Y270285D02*
X529300Y258700D01*
G01X516887Y269085D02*
X517217D01*
G01X517715Y270285D02*
X529300Y258700D01*
G01X516887Y270285D02*
X517715D01*
G01X532098Y258700D02*
X537442Y253356D01*
G01X531600Y257500D02*
X536242Y252858D01*
G01X529300Y258700D02*
X532098D01*
G01X528802Y257500D02*
X531600D01*
G01X517715Y270285D02*
X529300Y258700D01*
G01X522732Y263570D02*
X528802Y257500D01*
G01X521672Y263570D02*
X522732D01*
G01X519975Y266327D02*
X520823Y265479D01*
G01X518914Y266327D02*
X519975D01*
G01X517217Y269085D02*
X518066Y268236D01*
G01X516887Y269085D02*
X517217D01*
G01X516887Y270285D02*
X517715D01*
G01X516887Y269085D02*
X517217D01*
G01X523040Y251488D02*
X526514Y248014D01*
G01X524240Y251986D02*
X527714Y248512D01*
G01X523040Y253048D02*
Y251488D01*
G01X524240Y253546D02*
Y251986D01*
G01X518813Y257275D02*
X523040Y253048D01*
G01X519311Y258475D02*
X524240Y253546D01*
G01X518087Y257275D02*
X518813D01*
G01X518087Y258475D02*
X519311D01*
G01X524240Y251986D02*
X527714Y248512D01*
G01X523040Y251488D02*
X526514Y248014D01*
G01X524240Y253546D02*
Y251986D01*
G01X523040Y253048D02*
Y251488D01*
G01X519311Y258475D02*
X524240Y253546D01*
G01X518813Y257275D02*
X523040Y253048D01*
G01X518087Y258475D02*
X519311D01*
G01X518087Y257275D02*
X518813D01*
G01X518008Y245465D02*
X518700Y244773D01*
G01X518506Y246665D02*
X519900Y245271D01*
G01X517608Y245465D02*
X518008D01*
G01X517608Y246665D02*
X518506D01*
G01X571964Y339902D02*
X565512Y370257D01*
G01X564384Y369790D02*
X570737Y339902D01*
G01X568757Y324809D02*
X571964Y339902D01*
G01X570737D02*
X567629Y325276D01*
G01X562129Y314603D02*
X568757Y324809D01*
G01X561915Y316477D02*
X561261Y315471D01*
G01X564039Y319748D02*
X563385Y318742D01*
G01X567629Y325276D02*
X565509Y322013D01*
G01X557426Y311549D02*
X562129Y314603D01*
G01X561261Y315471D02*
X557070Y312749D01*
G01X549444Y311549D02*
X557426D01*
G01X557070Y312749D02*
X549444D01*
G01X548071Y310176D02*
G02X549444Y311549I1373J0D01*
G01Y312749D02*
G03X546871Y310176I0J-2573D01*
G01X548071Y309469D02*
Y310176D01*
G01X546871D02*
Y309410D01*
G01Y310176D02*
Y309410D01*
G01X548071Y309469D02*
Y310176D01*
G01X549444Y312749D02*
G03X546871Y310176I0J-2573D01*
G01X548071D02*
G02X549444Y311549I1373J0D01*
G01X557070Y312749D02*
X549444D01*
G01Y311549D02*
X557426D01*
G01X561261Y315471D02*
X557070Y312749D01*
G01X557426Y311549D02*
X562129Y314603D01*
G01X561915Y316477D02*
X561261Y315471D01*
G01X562129Y314603D02*
X568757Y324809D01*
G01X564039Y319748D02*
X563385Y318742D01*
G01X562129Y314603D02*
X568757Y324809D01*
G01X567629Y325276D02*
X565509Y322013D01*
G01X562129Y314603D02*
X568757Y324809D01*
G01X570737Y339902D02*
X567629Y325276D01*
G01X568757Y324809D02*
X571964Y339902D01*
G01X564384Y369790D02*
X570737Y339902D01*
G01X571964D02*
X565512Y370257D01*
G01X575937Y342816D02*
X569815Y371617D01*
G01X574710Y342816D02*
X568687Y371149D01*
G01X571409Y321507D02*
X575937Y342816D01*
G01X570281Y321974D02*
X574710Y342816D01*
G01X563265Y308967D02*
X571409Y321507D01*
G01X568689Y319523D02*
X570281Y321974D01*
G01X566564Y316252D02*
X567218Y317258D01*
G01X562397Y309835D02*
X565094Y313987D01*
G01X562064Y308187D02*
X563265Y308967D01*
G01X556743Y306163D02*
X562397Y309835D01*
G01X557487Y305214D02*
X562064Y308187D01*
G01X556743Y306163D02*
X562397Y309835D01*
G01X555723Y304540D02*
G03X557487Y305214I0J2645D01*
G01X555722Y305740D02*
G03X556743Y306163I0J1444D01*
G01X549898Y304540D02*
X555723D01*
G01X549898Y305740D02*
X555722D01*
G01X548043Y302685D02*
G02X549898Y304540I1855J0D01*
G01X546843Y302685D02*
G02X549898Y305740I3055J0D01*
G01X548043Y301978D02*
Y302685D01*
G01X546843Y301919D02*
Y302685D01*
G01X574710Y342816D02*
X568687Y371149D01*
G01X575937Y342816D02*
X569815Y371617D01*
G01X570281Y321974D02*
X574710Y342816D01*
G01X571409Y321507D02*
X575937Y342816D01*
G01X568689Y319523D02*
X570281Y321974D01*
G01X563265Y308967D02*
X571409Y321507D01*
G01X566564Y316252D02*
X567218Y317258D01*
G01X563265Y308967D02*
X571409Y321507D01*
G01X562397Y309835D02*
X565094Y313987D01*
G01X563265Y308967D02*
X571409Y321507D01*
G01X556743Y306163D02*
X562397Y309835D01*
G01X562064Y308187D02*
X563265Y308967D01*
G01X557487Y305214D02*
X562064Y308187D01*
G01X555722Y305740D02*
G03X556743Y306163I0J1444D01*
G01X555723Y304540D02*
G03X557487Y305214I0J2645D01*
G01X549898Y305740D02*
X555722D01*
G01X549898Y304540D02*
X555723D01*
G01X546843Y302685D02*
G02X549898Y305740I3055J0D01*
G01X548043Y302685D02*
G02X549898Y304540I1855J0D01*
G01X546843Y301919D02*
Y302685D01*
G01X548043Y301978D02*
Y302685D01*
G01X563522Y342279D02*
X558870Y364153D01*
G01X560097Y352614D02*
X557742Y363685D01*
G01X560908Y348799D02*
X560658Y349973D01*
G01X562295Y342279D02*
X561470Y346158D01*
G01X561173Y331225D02*
X563522Y342279D01*
G01X560045Y331693D02*
X562295Y342279D01*
G01X560514Y330210D02*
X561173Y331225D01*
G01X559646Y331079D02*
X560045Y331693D01*
G01X557123Y328012D02*
X560514Y330210D01*
G01X556635Y329126D02*
X559646Y331079D01*
G01X555120Y327501D02*
X557123Y328012D01*
G01X553014Y328203D02*
X556635Y329126D01*
G01X553165Y327003D02*
X555120Y327501D01*
G01X553014Y328203D02*
X556635Y329126D01*
G01X551566Y327003D02*
X553165D01*
G01X551565Y328203D02*
X553014D01*
G01X550009Y326358D02*
G02X551566Y327003I1557J-1557D01*
G01X549160Y327207D02*
G02X551565Y328203I2405J-2406D01*
G01X549740Y326089D02*
X550009Y326358D01*
G01X548891Y326938D02*
X549160Y327207D01*
G01X549477Y325454D02*
G02X549740Y326089I898J0D01*
G01X548277Y325454D02*
G02X548891Y326938I2098J1D01*
G01X549477Y324747D02*
Y325454D01*
G01X548277Y324688D02*
Y325454D01*
G01X560097Y352614D02*
X557742Y363685D01*
G01X563522Y342279D02*
X558870Y364153D01*
G01X560908Y348799D02*
X560658Y349973D01*
G01X563522Y342279D02*
X558870Y364153D01*
G01X562295Y342279D02*
X561470Y346158D01*
G01X563522Y342279D02*
X558870Y364153D01*
G01X560045Y331693D02*
X562295Y342279D01*
G01X561173Y331225D02*
X563522Y342279D01*
G01X559646Y331079D02*
X560045Y331693D01*
G01X560514Y330210D02*
X561173Y331225D01*
G01X556635Y329126D02*
X559646Y331079D01*
G01X557123Y328012D02*
X560514Y330210D01*
G01X553014Y328203D02*
X556635Y329126D01*
G01X555120Y327501D02*
X557123Y328012D01*
G01X553165Y327003D02*
X555120Y327501D01*
G01X551565Y328203D02*
X553014D01*
G01X551566Y327003D02*
X553165D01*
G01X549160Y327207D02*
G02X551565Y328203I2405J-2406D01*
G01X550009Y326358D02*
G02X551566Y327003I1557J-1557D01*
G01X548891Y326938D02*
X549160Y327207D01*
G01X549740Y326089D02*
X550009Y326358D01*
G01X548277Y325454D02*
G02X548891Y326938I2098J1D01*
G01X549477Y325454D02*
G02X549740Y326089I898J0D01*
G01X548277Y324688D02*
Y325454D01*
G01X549477Y324747D02*
Y325454D01*
G01X548128Y317307D02*
Y316436D01*
G01X546928Y316377D02*
Y317307D01*
G01X548449Y318082D02*
G03X548128Y317307I775J-775D01*
G01X547600Y318931D02*
G02X549224Y319603I1623J-1624D01*
G01X546928Y317307D02*
G02X547600Y318931I2296J1D01*
G01X549224Y318403D02*
G03X548449Y318082I0J-1096D01*
G01X547600Y318931D02*
G02X549224Y319603I1623J-1624D01*
G01X546928Y317307D02*
G02X547600Y318931I2296J1D01*
G01X555038Y318403D02*
X549224D01*
G01Y319603D02*
X554855D01*
G01X560542Y320116D02*
X555038Y318403D01*
G01X554855Y319603D02*
X559771Y321134D01*
G01X565298Y327435D02*
X560542Y320116D01*
G01X559771Y321134D02*
X564170Y327902D01*
G01X568087Y340562D02*
X565298Y327435D01*
G01X566369Y338254D02*
X566860Y340562D01*
G01X565559Y334439D02*
X565808Y335613D01*
G01X564170Y327903D02*
X564998Y331798D01*
G01X562246Y368058D02*
X568087Y340562D01*
G01X566860D02*
X561118Y367591D01*
G01X566860Y340562D02*
X561118Y367591D01*
G01X562246Y368058D02*
X568087Y340562D01*
G01X566369Y338254D02*
X566860Y340562D01*
G01X568087D02*
X565298Y327435D01*
G01X565559Y334439D02*
X565808Y335613D01*
G01X568087Y340562D02*
X565298Y327435D01*
G01X564170Y327903D02*
X564998Y331798D01*
G01X568087Y340562D02*
X565298Y327435D01*
G01X559771Y321134D02*
X564170Y327902D01*
G01X565298Y327435D02*
X560542Y320116D01*
G01X554855Y319603D02*
X559771Y321134D01*
G01X560542Y320116D02*
X555038Y318403D01*
G01X549224Y319603D02*
X554855D01*
G01X555038Y318403D02*
X549224D01*
G01X547600Y318931D02*
G02X549224Y319603I1623J-1624D01*
G01X548449Y318082D02*
G03X548128Y317307I775J-775D01*
G01X549224Y318403D02*
G03X548449Y318082I0J-1096D01*
G01X546928Y317307D02*
G02X547600Y318931I2296J1D01*
G01X548449Y318082D02*
G03X548128Y317307I775J-775D01*
G01X549224Y318403D02*
G03X548449Y318082I0J-1096D01*
G01X546928Y316377D02*
Y317307D01*
G01X548128D02*
Y316436D01*
G01X553241Y389154D02*
X536441Y400063D01*
G01X535974Y398935D02*
X552373Y388286D01*
G01X565512Y370257D02*
X553241Y389154D01*
G01X552373Y388286D02*
X564384Y369790D01*
G01X552373Y388286D02*
X564384Y369790D01*
G01X565512Y370257D02*
X553241Y389154D01*
G01X535974Y398935D02*
X552373Y388286D01*
G01X553241Y389154D02*
X536441Y400063D01*
G01X556744Y391670D02*
X536723Y404672D01*
G01X555877Y390802D02*
X536256Y403544D01*
G01X569815Y371617D02*
X556744Y391670D01*
G01X568687Y371149D02*
X555877Y390802D01*
G01D02*
X536256Y403544D01*
G01X556744Y391670D02*
X536723Y404672D01*
G01X568687Y371149D02*
X555877Y390802D01*
G01X569815Y371617D02*
X556744Y391670D01*
G01X546367Y383399D02*
X535367Y390545D01*
G01X545499Y382531D02*
X534900Y389417D01*
G01X558870Y364153D02*
X546367Y383399D01*
G01X557742Y363685D02*
X545499Y382531D01*
G01D02*
X534900Y389417D01*
G01X546367Y383399D02*
X535367Y390545D01*
G01X557742Y363685D02*
X545499Y382531D01*
G01X558870Y364153D02*
X546367Y383399D01*
G01X550164Y386669D02*
X562246Y368058D01*
G01X561118Y367591D02*
X549296Y385801D01*
G01X537486Y394902D02*
X550164Y386669D01*
G01X549296Y385801D02*
X537019Y393774D01*
G01X549296Y385801D02*
X537019Y393774D01*
G01X537486Y394902D02*
X550164Y386669D01*
G01X561118Y367591D02*
X549296Y385801D01*
G01X550164Y386669D02*
X562246Y368058D01*
G01X584532Y40739D02*
X585908D01*
G01X584532Y41939D02*
X585908D01*
G01X582471Y42800D02*
G03X584532Y40739I2061J0D01*
G01X583671Y42800D02*
G03X584532Y41939I861J0D01*
G01X582471Y53123D02*
Y42800D01*
G01X583671Y53250D02*
Y42800D01*
G01X584532Y41939D02*
X585908D01*
G01X584532Y40739D02*
X585908D01*
G01X583671Y42800D02*
G03X584532Y41939I861J0D01*
G01X582471Y42800D02*
G03X584532Y40739I2061J0D01*
G01X583671Y53250D02*
Y42800D01*
G01X582471Y53123D02*
Y42800D01*
G01X577446Y45463D02*
X578822D01*
G01X577446Y46663D02*
X578822D01*
G01X575385Y47524D02*
G03X577446Y45463I2061J0D01*
G01X576585Y47524D02*
G03X577446Y46663I861J0D01*
G01X575385Y62266D02*
Y47524D01*
G01X576585Y62393D02*
Y47524D01*
G01X577446Y46663D02*
X578822D01*
G01X577446Y45463D02*
X578822D01*
G01X576585Y47524D02*
G03X577446Y46663I861J0D01*
G01X575385Y47524D02*
G03X577446Y45463I2061J0D01*
G01X576585Y62393D02*
Y47524D01*
G01X575385Y62266D02*
Y47524D01*
G01X575205Y258599D02*
X579329Y239184D01*
G01X576333Y259066D02*
X580556Y239184D01*
G01X576333Y259066D02*
X580556Y239184D01*
G01X575205Y258599D02*
X579329Y239184D01*
G54D12*
G01X6250Y-135162D02*
Y-152662D01*
G01X1228Y-135162D02*
X11272D01*
G01X20038Y-152662D02*
Y-135162D01*
G01Y-143620D02*
X21130Y-142162D01*
X22222Y-141287D01*
X23968Y-140996D01*
X25278Y-141287D01*
X26807Y-142454D01*
X27462Y-144204D01*
Y-152662D01*
G01X41250Y-140996D02*
Y-152662D01*
G01Y-136329D02*
X40813Y-136037D01*
Y-135454D01*
X41250Y-135162D01*
X41687Y-135454D01*
Y-136037D01*
X41250Y-136329D01*
G01X55475Y-150621D02*
X56567Y-151787D01*
X58095Y-152662D01*
X59405D01*
X60715Y-152079D01*
X61588Y-151204D01*
X62025Y-150038D01*
X61807Y-148287D01*
X60933Y-147412D01*
X57003Y-145662D01*
X56130Y-143620D01*
X56567Y-142162D01*
X57440Y-141287D01*
X58750Y-140996D01*
X60060Y-141287D01*
X61370Y-142162D01*
G01X90693Y-157037D02*
X92222Y-158204D01*
X93968Y-158495D01*
X95496Y-158204D01*
X96807Y-156746D01*
X97680Y-154704D01*
Y-140996D01*
G01Y-143329D02*
X96807Y-142162D01*
X95496Y-141287D01*
X93968Y-140996D01*
X92222Y-141579D01*
X91130Y-142745D01*
X90256Y-144787D01*
X89820Y-146829D01*
X90038Y-148579D01*
X90912Y-150621D01*
X92222Y-152079D01*
X93968Y-152662D01*
X95278Y-152370D01*
X96807Y-151204D01*
X97680Y-150038D01*
G01X107975Y-144787D02*
X114962D01*
X114307Y-142745D01*
X113215Y-141579D01*
X111687Y-140996D01*
X110158Y-141287D01*
X108848Y-142162D01*
X107975Y-144204D01*
X107538Y-145954D01*
Y-147704D01*
X107975Y-149454D01*
X109067Y-151204D01*
X110377Y-152370D01*
X111905Y-152662D01*
X113433Y-152079D01*
X114962Y-150329D01*
G01X125693Y-152662D02*
Y-140996D01*
G01Y-143329D02*
X126785Y-142162D01*
X127877Y-141287D01*
X129405Y-140996D01*
X130496Y-141287D01*
X131807Y-142162D01*
G01X142320Y-152662D02*
Y-135162D01*
G01Y-143912D02*
X143412Y-142162D01*
X144722Y-141287D01*
X146032Y-140996D01*
X147996Y-141579D01*
X149307Y-142745D01*
X150180Y-144787D01*
Y-147120D01*
X149743Y-149454D01*
X148870Y-151204D01*
X147342Y-152370D01*
X146032Y-152662D01*
X144722Y-152370D01*
X143412Y-151496D01*
X142320Y-150038D01*
G01X160475Y-144787D02*
X167462D01*
X166807Y-142745D01*
X165715Y-141579D01*
X164187Y-140996D01*
X162658Y-141287D01*
X161348Y-142162D01*
X160475Y-144204D01*
X160038Y-145954D01*
Y-147704D01*
X160475Y-149454D01*
X161567Y-151204D01*
X162877Y-152370D01*
X164405Y-152662D01*
X165933Y-152079D01*
X167462Y-150329D01*
G01X178193Y-152662D02*
Y-140996D01*
G01Y-143329D02*
X179285Y-142162D01*
X180377Y-141287D01*
X181905Y-140996D01*
X182996Y-141287D01*
X184307Y-142162D01*
G01X216250Y-140996D02*
Y-152662D01*
G01Y-136329D02*
X215813Y-136037D01*
Y-135454D01*
X216250Y-135162D01*
X216687Y-135454D01*
Y-136037D01*
X216250Y-136329D01*
G01X230475Y-150621D02*
X231567Y-151787D01*
X233095Y-152662D01*
X234405D01*
X235715Y-152079D01*
X236588Y-151204D01*
X237025Y-150038D01*
X236807Y-148287D01*
X235933Y-147412D01*
X232003Y-145662D01*
X231130Y-143620D01*
X231567Y-142162D01*
X232440Y-141287D01*
X233750Y-140996D01*
X235060Y-141287D01*
X236370Y-142162D01*
G01X265256Y-157037D02*
X266785Y-158204D01*
X268095Y-158495D01*
X269842Y-157912D01*
X271152Y-156454D01*
X271807Y-153828D01*
Y-140996D01*
G01Y-136329D02*
X271370Y-136037D01*
Y-135454D01*
X271807Y-135162D01*
X272243Y-135454D01*
Y-136037D01*
X271807Y-136329D01*
G01X282538Y-140996D02*
Y-149162D01*
X283412Y-151204D01*
X284722Y-152370D01*
X286250Y-152662D01*
X287778Y-152370D01*
X289088Y-151204D01*
X289962Y-149162D01*
G01Y-152662D02*
Y-140996D01*
G01X300475Y-150621D02*
X301567Y-151787D01*
X303095Y-152662D01*
X304405D01*
X305715Y-152079D01*
X306588Y-151204D01*
X307025Y-150038D01*
X306807Y-148287D01*
X305933Y-147412D01*
X302003Y-145662D01*
X301130Y-143620D01*
X301567Y-142162D01*
X302440Y-141287D01*
X303750Y-140996D01*
X305060Y-141287D01*
X306370Y-142162D01*
G01X321250Y-135162D02*
Y-152662D01*
G01X318193Y-140996D02*
X324307D01*
G01X354940Y-152662D02*
Y-137787D01*
X355377Y-136329D01*
X356250Y-135454D01*
X357560Y-135162D01*
X358870Y-135745D01*
X359525Y-137204D01*
G01X356905Y-142162D02*
X352538D01*
G01X373750Y-152662D02*
X372440Y-152370D01*
X371130Y-151204D01*
X370256Y-149162D01*
X369820Y-146829D01*
X370256Y-144495D01*
X371130Y-142454D01*
X372440Y-141287D01*
X373750Y-140996D01*
X375060Y-141287D01*
X376370Y-142454D01*
X377243Y-144495D01*
X377462Y-146829D01*
X377243Y-149162D01*
X376370Y-151204D01*
X375060Y-152370D01*
X373750Y-152662D01*
G01X388193D02*
Y-140996D01*
G01Y-143329D02*
X389285Y-142162D01*
X390377Y-141287D01*
X391905Y-140996D01*
X392996Y-141287D01*
X394307Y-142162D01*
G01X421665Y-157912D02*
X422975Y-158495D01*
X424722Y-157912D01*
X425813Y-156746D01*
X426687Y-155287D01*
X427996Y-150621D01*
X430835Y-140996D01*
G01X423848D02*
X427996Y-150621D01*
G01X443750Y-152662D02*
X442440Y-152370D01*
X441130Y-151204D01*
X440256Y-149162D01*
X439820Y-146829D01*
X440256Y-144495D01*
X441130Y-142454D01*
X442440Y-141287D01*
X443750Y-140996D01*
X445060Y-141287D01*
X446370Y-142454D01*
X447243Y-144495D01*
X447462Y-146829D01*
X447243Y-149162D01*
X446370Y-151204D01*
X445060Y-152370D01*
X443750Y-152662D01*
G01X457538Y-140996D02*
Y-149162D01*
X458412Y-151204D01*
X459722Y-152370D01*
X461250Y-152662D01*
X462778Y-152370D01*
X464088Y-151204D01*
X464962Y-149162D01*
G01Y-152662D02*
Y-140996D01*
G01X475693Y-152662D02*
Y-140996D01*
G01Y-143329D02*
X476785Y-142162D01*
X477877Y-141287D01*
X479405Y-140996D01*
X480496Y-141287D01*
X481807Y-142162D01*
G01X510693Y-152662D02*
Y-140996D01*
G01Y-143329D02*
X511785Y-142162D01*
X512877Y-141287D01*
X514405Y-140996D01*
X515496Y-141287D01*
X516807Y-142162D01*
G01X527975Y-144787D02*
X534962D01*
X534307Y-142745D01*
X533215Y-141579D01*
X531687Y-140996D01*
X530158Y-141287D01*
X528848Y-142162D01*
X527975Y-144204D01*
X527538Y-145954D01*
Y-147704D01*
X527975Y-149454D01*
X529067Y-151204D01*
X530377Y-152370D01*
X531905Y-152662D01*
X533433Y-152079D01*
X534962Y-150329D01*
G01X547440Y-152662D02*
Y-137787D01*
X547877Y-136329D01*
X548750Y-135454D01*
X550060Y-135162D01*
X551370Y-135745D01*
X552025Y-137204D01*
G01X549405Y-142162D02*
X545038D01*
G01X562975Y-144787D02*
X569962D01*
X569307Y-142745D01*
X568215Y-141579D01*
X566687Y-140996D01*
X565158Y-141287D01*
X563848Y-142162D01*
X562975Y-144204D01*
X562538Y-145954D01*
Y-147704D01*
X562975Y-149454D01*
X564067Y-151204D01*
X565377Y-152370D01*
X566905Y-152662D01*
X568433Y-152079D01*
X569962Y-150329D01*
G01X580693Y-152662D02*
Y-140996D01*
G01Y-143329D02*
X581785Y-142162D01*
X582877Y-141287D01*
X584405Y-140996D01*
X585496Y-141287D01*
X586807Y-142162D01*
G01X597975Y-144787D02*
X604962D01*
X604307Y-142745D01*
X603215Y-141579D01*
X601687Y-140996D01*
X600158Y-141287D01*
X598848Y-142162D01*
X597975Y-144204D01*
X597538Y-145954D01*
Y-147704D01*
X597975Y-149454D01*
X599067Y-151204D01*
X600377Y-152370D01*
X601905Y-152662D01*
X603433Y-152079D01*
X604962Y-150329D01*
G01X615038Y-152662D02*
Y-140996D01*
G01Y-143912D02*
X615912Y-142454D01*
X617222Y-141287D01*
X618968Y-140996D01*
X620496Y-141287D01*
X621807Y-142454D01*
X622462Y-144495D01*
Y-152662D01*
G01X639743Y-142454D02*
X638215Y-141287D01*
X636905Y-140996D01*
X635158Y-141579D01*
X633848Y-142745D01*
X632975Y-144787D01*
X632756Y-146829D01*
X632975Y-148871D01*
X633848Y-150621D01*
X635158Y-152079D01*
X636905Y-152662D01*
X638433Y-152079D01*
X639743Y-150912D01*
G01X650475Y-144787D02*
X657462D01*
X656807Y-142745D01*
X655715Y-141579D01*
X654187Y-140996D01*
X652658Y-141287D01*
X651348Y-142162D01*
X650475Y-144204D01*
X650038Y-145954D01*
Y-147704D01*
X650475Y-149454D01*
X651567Y-151204D01*
X652877Y-152370D01*
X654405Y-152662D01*
X655933Y-152079D01*
X657462Y-150329D01*
G01X688750Y-135162D02*
Y-152662D01*
G01X685693Y-140996D02*
X691807D01*
G01X706250Y-152662D02*
X704940Y-152370D01*
X703630Y-151204D01*
X702756Y-149162D01*
X702320Y-146829D01*
X702756Y-144495D01*
X703630Y-142454D01*
X704940Y-141287D01*
X706250Y-140996D01*
X707560Y-141287D01*
X708870Y-142454D01*
X709743Y-144495D01*
X709962Y-146829D01*
X709743Y-149162D01*
X708870Y-151204D01*
X707560Y-152370D01*
X706250Y-152662D01*
G01X739940D02*
Y-137787D01*
X740377Y-136329D01*
X741250Y-135454D01*
X742560Y-135162D01*
X743870Y-135745D01*
X744525Y-137204D01*
G01X741905Y-142162D02*
X737538D01*
G01X758750Y-140996D02*
Y-152662D01*
G01Y-136329D02*
X758313Y-136037D01*
Y-135454D01*
X758750Y-135162D01*
X759187Y-135454D01*
Y-136037D01*
X758750Y-136329D01*
G01X772538Y-152662D02*
Y-140996D01*
G01Y-143912D02*
X773412Y-142454D01*
X774722Y-141287D01*
X776468Y-140996D01*
X777996Y-141287D01*
X779307Y-142454D01*
X779962Y-144495D01*
Y-152662D01*
G01X797680Y-135162D02*
Y-152662D01*
G01Y-150038D02*
X796807Y-151496D01*
X795496Y-152370D01*
X793968Y-152662D01*
X792222Y-152079D01*
X790912Y-150621D01*
X790038Y-148871D01*
X789820Y-146829D01*
X790038Y-144787D01*
X790912Y-143037D01*
X792222Y-141579D01*
X793968Y-140996D01*
X795496Y-141287D01*
X796588Y-141871D01*
X797680Y-143037D01*
G01X828750Y-135162D02*
Y-152662D01*
G01X825693Y-140996D02*
X831807D01*
G01X842538Y-152662D02*
Y-135162D01*
G01Y-143620D02*
X843630Y-142162D01*
X844722Y-141287D01*
X846468Y-140996D01*
X847778Y-141287D01*
X849307Y-142454D01*
X849962Y-144204D01*
Y-152662D01*
G01X860475Y-144787D02*
X867462D01*
X866807Y-142745D01*
X865715Y-141579D01*
X864187Y-140996D01*
X862658Y-141287D01*
X861348Y-142162D01*
X860475Y-144204D01*
X860038Y-145954D01*
Y-147704D01*
X860475Y-149454D01*
X861567Y-151204D01*
X862877Y-152370D01*
X864405Y-152662D01*
X865933Y-152079D01*
X867462Y-150329D01*
G01X893947Y-152662D02*
Y-135162D01*
X898313D01*
X900060Y-136037D01*
X901370Y-137204D01*
X902462Y-138953D01*
X903335Y-140996D01*
X903553Y-143912D01*
X903335Y-146829D01*
X902462Y-148871D01*
X901370Y-150621D01*
X900060Y-151787D01*
X898313Y-152662D01*
X893947D01*
G01X911883D02*
Y-135162D01*
X917123D01*
X918870Y-136037D01*
X920180Y-138079D01*
X920617Y-140412D01*
X920180Y-142745D01*
X919088Y-144495D01*
X917123Y-145371D01*
X911883D01*
G01X951250Y-140996D02*
Y-152662D01*
G01Y-136329D02*
X950813Y-136037D01*
Y-135454D01*
X951250Y-135162D01*
X951687Y-135454D01*
Y-136037D01*
X951250Y-136329D01*
G01X962200Y-152662D02*
Y-140996D01*
G01Y-144204D02*
X962855Y-142745D01*
X963947Y-141579D01*
X965475Y-140996D01*
X967003Y-141579D01*
X968095Y-142745D01*
X968750Y-144204D01*
Y-152662D01*
G01Y-144204D02*
X969405Y-142745D01*
X970496Y-141579D01*
X972025Y-140996D01*
X973553Y-141579D01*
X974645Y-142745D01*
X975300Y-144495D01*
Y-152662D01*
G01X982320Y-158495D02*
Y-140996D01*
G01Y-143620D02*
X983412Y-142162D01*
X984503Y-141287D01*
X986250Y-140996D01*
X987778Y-141287D01*
X989307Y-142745D01*
X989962Y-144787D01*
X990180Y-146829D01*
X989962Y-148871D01*
X989307Y-150912D01*
X987996Y-152079D01*
X986250Y-152662D01*
X984722Y-152370D01*
X983193Y-151496D01*
X982320Y-150329D01*
G01X1000475Y-144787D02*
X1007462D01*
X1006807Y-142745D01*
X1005715Y-141579D01*
X1004187Y-140996D01*
X1002658Y-141287D01*
X1001348Y-142162D01*
X1000475Y-144204D01*
X1000038Y-145954D01*
Y-147704D01*
X1000475Y-149454D01*
X1001567Y-151204D01*
X1002877Y-152370D01*
X1004405Y-152662D01*
X1005933Y-152079D01*
X1007462Y-150329D01*
G01X1025180Y-135162D02*
Y-152662D01*
G01Y-150038D02*
X1024307Y-151496D01*
X1022996Y-152370D01*
X1021468Y-152662D01*
X1019722Y-152079D01*
X1018412Y-150621D01*
X1017538Y-148871D01*
X1017320Y-146829D01*
X1017538Y-144787D01*
X1018412Y-143037D01*
X1019722Y-141579D01*
X1021468Y-140996D01*
X1022996Y-141287D01*
X1024088Y-141871D01*
X1025180Y-143037D01*
G01X1042680Y-152662D02*
Y-140996D01*
G01Y-143037D02*
X1041807Y-141871D01*
X1040496Y-141287D01*
X1038968Y-140996D01*
X1037440Y-141579D01*
X1036130Y-142745D01*
X1035256Y-144495D01*
X1034820Y-146829D01*
X1035256Y-149162D01*
X1036130Y-150912D01*
X1037440Y-152079D01*
X1038968Y-152662D01*
X1040496Y-152370D01*
X1041807Y-151496D01*
X1042680Y-150329D01*
G01X1052538Y-152662D02*
Y-140996D01*
G01Y-143912D02*
X1053412Y-142454D01*
X1054722Y-141287D01*
X1056468Y-140996D01*
X1057996Y-141287D01*
X1059307Y-142454D01*
X1059962Y-144495D01*
Y-152662D01*
G01X1077243Y-142454D02*
X1075715Y-141287D01*
X1074405Y-140996D01*
X1072658Y-141579D01*
X1071348Y-142745D01*
X1070475Y-144787D01*
X1070256Y-146829D01*
X1070475Y-148871D01*
X1071348Y-150621D01*
X1072658Y-152079D01*
X1074405Y-152662D01*
X1075933Y-152079D01*
X1077243Y-150912D01*
G01X1087975Y-144787D02*
X1094962D01*
X1094307Y-142745D01*
X1093215Y-141579D01*
X1091687Y-140996D01*
X1090158Y-141287D01*
X1088848Y-142162D01*
X1087975Y-144204D01*
X1087538Y-145954D01*
Y-147704D01*
X1087975Y-149454D01*
X1089067Y-151204D01*
X1090377Y-152370D01*
X1091905Y-152662D01*
X1093433Y-152079D01*
X1094962Y-150329D01*
G01X1126250Y-135162D02*
Y-152662D01*
G01X1123193Y-140996D02*
X1129307D01*
G01X1140693Y-152662D02*
Y-140996D01*
G01Y-143329D02*
X1141785Y-142162D01*
X1142877Y-141287D01*
X1144405Y-140996D01*
X1145496Y-141287D01*
X1146807Y-142162D01*
G01X1165180Y-152662D02*
Y-140996D01*
G01Y-143037D02*
X1164307Y-141871D01*
X1162996Y-141287D01*
X1161468Y-140996D01*
X1159940Y-141579D01*
X1158630Y-142745D01*
X1157756Y-144495D01*
X1157320Y-146829D01*
X1157756Y-149162D01*
X1158630Y-150912D01*
X1159940Y-152079D01*
X1161468Y-152662D01*
X1162996Y-152370D01*
X1164307Y-151496D01*
X1165180Y-150329D01*
G01X1182243Y-142454D02*
X1180715Y-141287D01*
X1179405Y-140996D01*
X1177658Y-141579D01*
X1176348Y-142745D01*
X1175475Y-144787D01*
X1175256Y-146829D01*
X1175475Y-148871D01*
X1176348Y-150621D01*
X1177658Y-152079D01*
X1179405Y-152662D01*
X1180933Y-152079D01*
X1182243Y-150912D01*
G01X1192975Y-144787D02*
X1199962D01*
X1199307Y-142745D01*
X1198215Y-141579D01*
X1196687Y-140996D01*
X1195158Y-141287D01*
X1193848Y-142162D01*
X1192975Y-144204D01*
X1192538Y-145954D01*
Y-147704D01*
X1192975Y-149454D01*
X1194067Y-151204D01*
X1195377Y-152370D01*
X1196905Y-152662D01*
X1198433Y-152079D01*
X1199962Y-150329D01*
G01X1210475Y-150621D02*
X1211567Y-151787D01*
X1213095Y-152662D01*
X1214405D01*
X1215715Y-152079D01*
X1216588Y-151204D01*
X1217025Y-150038D01*
X1216807Y-148287D01*
X1215933Y-147412D01*
X1212003Y-145662D01*
X1211130Y-143620D01*
X1211567Y-142162D01*
X1212440Y-141287D01*
X1213750Y-140996D01*
X1215060Y-141287D01*
X1216370Y-142162D01*
G01X1248750Y-140996D02*
Y-152662D01*
G01Y-136329D02*
X1248313Y-136037D01*
Y-135454D01*
X1248750Y-135162D01*
X1249187Y-135454D01*
Y-136037D01*
X1248750Y-136329D01*
G01X1262538Y-152662D02*
Y-140996D01*
G01Y-143912D02*
X1263412Y-142454D01*
X1264722Y-141287D01*
X1266468Y-140996D01*
X1267996Y-141287D01*
X1269307Y-142454D01*
X1269962Y-144495D01*
Y-152662D01*
G01X1301250D02*
Y-135162D01*
G01X1322680Y-152662D02*
Y-140996D01*
G01Y-143037D02*
X1321807Y-141871D01*
X1320496Y-141287D01*
X1318968Y-140996D01*
X1317440Y-141579D01*
X1316130Y-142745D01*
X1315256Y-144495D01*
X1314820Y-146829D01*
X1315256Y-149162D01*
X1316130Y-150912D01*
X1317440Y-152079D01*
X1318968Y-152662D01*
X1320496Y-152370D01*
X1321807Y-151496D01*
X1322680Y-150329D01*
G01X1331665Y-157912D02*
X1332975Y-158495D01*
X1334722Y-157912D01*
X1335813Y-156746D01*
X1336687Y-155287D01*
X1337996Y-150621D01*
X1340835Y-140996D01*
G01X1333848D02*
X1337996Y-150621D01*
G01X1350475Y-144787D02*
X1357462D01*
X1356807Y-142745D01*
X1355715Y-141579D01*
X1354187Y-140996D01*
X1352658Y-141287D01*
X1351348Y-142162D01*
X1350475Y-144204D01*
X1350038Y-145954D01*
Y-147704D01*
X1350475Y-149454D01*
X1351567Y-151204D01*
X1352877Y-152370D01*
X1354405Y-152662D01*
X1355933Y-152079D01*
X1357462Y-150329D01*
G01X1368193Y-152662D02*
Y-140996D01*
G01Y-143329D02*
X1369285Y-142162D01*
X1370377Y-141287D01*
X1371905Y-140996D01*
X1372996Y-141287D01*
X1374307Y-142162D01*
G01X1401883Y-135162D02*
Y-152662D01*
X1410617D01*
G01X1419602Y-145371D02*
X1421130Y-143329D01*
X1422440Y-142162D01*
X1424187Y-141579D01*
X1425715Y-142162D01*
X1426807Y-143329D01*
X1427680Y-145079D01*
X1427898Y-147120D01*
X1427680Y-148871D01*
X1426807Y-150621D01*
X1425496Y-152079D01*
X1423968Y-152662D01*
X1422222Y-152079D01*
X1420693Y-150329D01*
X1419820Y-147704D01*
X1419602Y-144787D01*
X1420038Y-140996D01*
X1420693Y-138953D01*
X1421785Y-136912D01*
X1423313Y-135454D01*
X1424842Y-135162D01*
X1426370Y-135745D01*
X1427462Y-137204D01*
G01X1441250Y-153245D02*
X1440813Y-152954D01*
Y-152370D01*
X1441250Y-152079D01*
X1441687Y-152370D01*
Y-152954D01*
X1441250Y-153245D01*
G01X878818Y546266D02*
Y563766D01*
X883184D01*
X884931Y562891D01*
X886241Y561724D01*
X887333Y559975D01*
X888206Y557932D01*
X888424Y555016D01*
X888206Y552099D01*
X887333Y550057D01*
X886241Y548307D01*
X884931Y547141D01*
X883184Y546266D01*
X878818D01*
G01X896754D02*
Y563766D01*
X901994D01*
X903741Y562891D01*
X905051Y560849D01*
X905488Y558516D01*
X905051Y556183D01*
X903959Y554433D01*
X901994Y553557D01*
X896754D01*
G01X933501Y563766D02*
X938741D01*
G01X936121D02*
Y546266D01*
G01X933501D02*
X938741D01*
G01X947944D02*
Y563766D01*
X953621Y549183D01*
X959298Y563766D01*
Y546266D01*
G01X966754D02*
Y563766D01*
X971994D01*
X973741Y562891D01*
X975051Y560849D01*
X975488Y558516D01*
X975051Y556183D01*
X973959Y554433D01*
X971994Y553557D01*
X966754D01*
G01X992988Y546266D02*
X984254D01*
Y563766D01*
X992988D01*
G01X989494Y555308D02*
X984254D01*
G01X1001318Y546266D02*
Y563766D01*
X1005684D01*
X1007431Y562891D01*
X1008741Y561724D01*
X1009833Y559975D01*
X1010706Y557932D01*
X1010924Y555016D01*
X1010706Y552099D01*
X1009833Y550057D01*
X1008741Y548307D01*
X1007431Y547141D01*
X1005684Y546266D01*
X1001318D01*
G01X1018162D02*
X1023621Y563766D01*
X1029080Y546266D01*
G01X1027114Y552391D02*
X1020127D01*
G01X1036099Y546266D02*
Y563766D01*
X1046143Y546266D01*
Y563766D01*
G01X1063424Y562307D02*
X1062114Y563183D01*
X1060586Y563766D01*
X1058839D01*
X1056874Y562891D01*
X1055346Y561433D01*
X1054254Y559682D01*
X1053381Y556766D01*
X1053162Y554141D01*
X1053599Y551516D01*
X1054254Y549766D01*
X1055564Y548016D01*
X1057093Y546849D01*
X1058621Y546266D01*
X1060149D01*
X1061678Y546849D01*
X1062988Y547724D01*
X1064080Y548890D01*
G01X1080488Y546266D02*
X1071754D01*
Y563766D01*
X1080488D01*
G01X1076994Y555308D02*
X1071754D01*
G01X1111121Y563766D02*
Y546266D01*
G01X1106099Y563766D02*
X1116143D01*
G01X1123162Y546266D02*
X1128621Y563766D01*
X1134080Y546266D01*
G01X1132114Y552391D02*
X1125127D01*
G01X1147867Y555599D02*
X1148741Y556474D01*
X1149396Y557932D01*
X1149833Y559975D01*
X1149396Y561724D01*
X1148523Y562891D01*
X1146994Y563766D01*
X1141099D01*
Y546266D01*
X1148304D01*
X1149833Y547432D01*
X1150706Y549183D01*
X1151143Y551224D01*
X1150706Y553266D01*
X1149396Y555016D01*
X1147867Y555599D01*
X1141099D01*
G01X1159254Y563766D02*
Y546266D01*
X1167988D01*
G01X1185488D02*
X1176754D01*
Y563766D01*
X1185488D01*
G01X1181994Y555308D02*
X1176754D01*
G01X1198621Y545683D02*
X1198184Y545974D01*
Y546558D01*
X1198621Y546849D01*
X1199058Y546558D01*
Y545974D01*
X1198621Y545683D01*
G01Y553557D02*
X1198184Y553849D01*
Y554433D01*
X1198621Y554724D01*
X1199058Y554433D01*
Y553849D01*
X1198621Y553557D01*
G01X1229254Y563766D02*
Y546266D01*
X1237988D01*
G01X1246973Y553557D02*
X1248501Y555599D01*
X1249811Y556766D01*
X1251558Y557349D01*
X1253086Y556766D01*
X1254178Y555599D01*
X1255051Y553849D01*
X1255269Y551808D01*
X1255051Y550057D01*
X1254178Y548307D01*
X1252867Y546849D01*
X1251339Y546266D01*
X1249593Y546849D01*
X1248064Y548599D01*
X1247191Y551224D01*
X1246973Y554141D01*
X1247409Y557932D01*
X1248064Y559975D01*
X1249156Y562016D01*
X1250684Y563474D01*
X1252213Y563766D01*
X1253741Y563183D01*
X1254833Y561724D01*
G01X924768Y407083D02*
X934374Y419916D01*
G01X929571Y422249D02*
Y404749D01*
G01X934374Y407083D02*
X924768Y419916D01*
G01X923021Y413499D02*
X936121D01*
G01X947071Y407666D02*
X948599Y407958D01*
X950346Y408832D01*
X951438Y410290D01*
X951874Y412333D01*
X951438Y414374D01*
X950128Y416124D01*
X948163Y416999D01*
X945979D01*
X944669Y417583D01*
X943577Y419041D01*
X943141Y421082D01*
X943796Y423124D01*
X945324Y424583D01*
X947071Y425166D01*
X948817Y424583D01*
X950346Y423124D01*
X951001Y421082D01*
X950564Y419041D01*
X949473Y417583D01*
X948163Y416999D01*
X945979D01*
X944014Y416124D01*
X942704Y414374D01*
X942268Y412333D01*
X942704Y410290D01*
X943796Y408832D01*
X945543Y407958D01*
X947071Y407666D01*
G01X964571D02*
X966099Y407958D01*
X967846Y408832D01*
X968938Y410290D01*
X969374Y412333D01*
X968938Y414374D01*
X967628Y416124D01*
X965663Y416999D01*
X963479D01*
X962169Y417583D01*
X961077Y419041D01*
X960641Y421082D01*
X961296Y423124D01*
X962824Y424583D01*
X964571Y425166D01*
X966317Y424583D01*
X967846Y423124D01*
X968501Y421082D01*
X968064Y419041D01*
X966973Y417583D01*
X965663Y416999D01*
X963479D01*
X961514Y416124D01*
X960204Y414374D01*
X959768Y412333D01*
X960204Y410290D01*
X961296Y408832D01*
X963043Y407958D01*
X964571Y407666D01*
G01X982071Y407083D02*
X981634Y407374D01*
Y407958D01*
X982071Y408249D01*
X982508Y407958D01*
Y407374D01*
X982071Y407083D01*
G01X999571Y425166D02*
X997824Y424583D01*
X996514Y423124D01*
X995641Y421375D01*
X994986Y419041D01*
X994768Y416416D01*
X994986Y413791D01*
X995641Y411457D01*
X996514Y409707D01*
X997824Y408249D01*
X999571Y407666D01*
X1001317Y408249D01*
X1002628Y409707D01*
X1003501Y411457D01*
X1004156Y413791D01*
X1004374Y416416D01*
X1004156Y419041D01*
X1003501Y421375D01*
X1002628Y423124D01*
X1001317Y424583D01*
X999571Y425166D01*
G01X929571Y373016D02*
Y390516D01*
X926951Y387016D01*
G01Y373016D02*
X932191D01*
G01X947071Y390516D02*
X945324Y389933D01*
X944014Y388474D01*
X943141Y386725D01*
X942486Y384391D01*
X942268Y381766D01*
X942486Y379141D01*
X943141Y376807D01*
X944014Y375057D01*
X945324Y373599D01*
X947071Y373016D01*
X948817Y373599D01*
X950128Y375057D01*
X951001Y376807D01*
X951656Y379141D01*
X951874Y381766D01*
X951656Y384391D01*
X951001Y386725D01*
X950128Y388474D01*
X948817Y389933D01*
X947071Y390516D01*
G01X964571D02*
X962824Y389933D01*
X961514Y388474D01*
X960641Y386725D01*
X959986Y384391D01*
X959768Y381766D01*
X959986Y379141D01*
X960641Y376807D01*
X961514Y375057D01*
X962824Y373599D01*
X964571Y373016D01*
X966317Y373599D01*
X967628Y375057D01*
X968501Y376807D01*
X969156Y379141D01*
X969374Y381766D01*
X969156Y384391D01*
X968501Y386725D01*
X967628Y388474D01*
X966317Y389933D01*
X964571Y390516D01*
G01X982071Y372433D02*
X981634Y372724D01*
Y373308D01*
X982071Y373599D01*
X982508Y373308D01*
Y372724D01*
X982071Y372433D01*
G01X999571Y390516D02*
X997824Y389933D01*
X996514Y388474D01*
X995641Y386725D01*
X994986Y384391D01*
X994768Y381766D01*
X994986Y379141D01*
X995641Y376807D01*
X996514Y375057D01*
X997824Y373599D01*
X999571Y373016D01*
X1001317Y373599D01*
X1002628Y375057D01*
X1003501Y376807D01*
X1004156Y379141D01*
X1004374Y381766D01*
X1004156Y384391D01*
X1003501Y386725D01*
X1002628Y388474D01*
X1001317Y389933D01*
X999571Y390516D01*
G01X924768Y476383D02*
X934374Y489216D01*
G01X929571Y491549D02*
Y474049D01*
G01X934374Y476383D02*
X924768Y489216D01*
G01X923021Y482799D02*
X936121D01*
G01X947071Y476966D02*
X948599Y477258D01*
X950346Y478132D01*
X951438Y479590D01*
X951874Y481633D01*
X951438Y483674D01*
X950128Y485424D01*
X948163Y486299D01*
X945979D01*
X944669Y486883D01*
X943577Y488341D01*
X943141Y490382D01*
X943796Y492424D01*
X945324Y493883D01*
X947071Y494466D01*
X948817Y493883D01*
X950346Y492424D01*
X951001Y490382D01*
X950564Y488341D01*
X949473Y486883D01*
X948163Y486299D01*
X945979D01*
X944014Y485424D01*
X942704Y483674D01*
X942268Y481633D01*
X942704Y479590D01*
X943796Y478132D01*
X945543Y477258D01*
X947071Y476966D01*
G01X959768Y480466D02*
X961077Y478424D01*
X962824Y477258D01*
X964789Y476966D01*
X966536Y477258D01*
X968283Y478716D01*
X969374Y480466D01*
X969593Y482216D01*
X969156Y484257D01*
X967628Y485716D01*
X966099Y486299D01*
X964134D01*
G01X966099D02*
X967409Y487174D01*
X968501Y488632D01*
X968938Y490382D01*
X968501Y492133D01*
X967409Y493591D01*
X965444Y494466D01*
X963479Y494174D01*
X961514Y493007D01*
G01X982071Y476383D02*
X981634Y476674D01*
Y477258D01*
X982071Y477549D01*
X982508Y477258D01*
Y476674D01*
X982071Y476383D01*
G01X999571Y494466D02*
X997824Y493883D01*
X996514Y492424D01*
X995641Y490675D01*
X994986Y488341D01*
X994768Y485716D01*
X994986Y483091D01*
X995641Y480757D01*
X996514Y479007D01*
X997824Y477549D01*
X999571Y476966D01*
X1001317Y477549D01*
X1002628Y479007D01*
X1003501Y480757D01*
X1004156Y483091D01*
X1004374Y485716D01*
X1004156Y488341D01*
X1003501Y490675D01*
X1002628Y492424D01*
X1001317Y493883D01*
X999571Y494466D01*
G01X938321Y442316D02*
X939849Y442608D01*
X941596Y443482D01*
X942688Y444940D01*
X943124Y446983D01*
X942688Y449024D01*
X941378Y450774D01*
X939413Y451649D01*
X937229D01*
X935919Y452233D01*
X934827Y453691D01*
X934391Y455732D01*
X935046Y457774D01*
X936574Y459233D01*
X938321Y459816D01*
X940067Y459233D01*
X941596Y457774D01*
X942251Y455732D01*
X941814Y453691D01*
X940723Y452233D01*
X939413Y451649D01*
X937229D01*
X935264Y450774D01*
X933954Y449024D01*
X933518Y446983D01*
X933954Y444940D01*
X935046Y443482D01*
X936793Y442608D01*
X938321Y442316D01*
G01X951018Y444940D02*
X952327Y443482D01*
X953856Y442608D01*
X955821Y442316D01*
X957786Y442899D01*
X959314Y444066D01*
X960406Y446107D01*
X960624Y448441D01*
X960188Y450774D01*
X959096Y452233D01*
X957567Y453399D01*
X956039Y453691D01*
X954511Y453399D01*
X952546Y452233D01*
X953201Y459816D01*
X959096D01*
G01X973321Y441733D02*
X972884Y442024D01*
Y442608D01*
X973321Y442899D01*
X973758Y442608D01*
Y442024D01*
X973321Y441733D01*
G01X990821Y459816D02*
X989074Y459233D01*
X987764Y457774D01*
X986891Y456025D01*
X986236Y453691D01*
X986018Y451066D01*
X986236Y448441D01*
X986891Y446107D01*
X987764Y444357D01*
X989074Y442899D01*
X990821Y442316D01*
X992567Y442899D01*
X993878Y444357D01*
X994751Y446107D01*
X995406Y448441D01*
X995624Y451066D01*
X995406Y453691D01*
X994751Y456025D01*
X993878Y457774D01*
X992567Y459233D01*
X990821Y459816D01*
G01X900701Y529116D02*
X905941D01*
G01X903321D02*
Y511616D01*
G01X900701D02*
X905941D01*
G01X915144D02*
Y529116D01*
X920821Y514533D01*
X926498Y529116D01*
Y511616D01*
G01X933954D02*
Y529116D01*
X939194D01*
X940941Y528241D01*
X942251Y526199D01*
X942688Y523866D01*
X942251Y521533D01*
X941159Y519783D01*
X939194Y518907D01*
X933954D01*
G01X954729Y505783D02*
X952546Y508699D01*
X951454Y511616D01*
Y523282D01*
X952546Y526199D01*
X954729Y529116D01*
G01X973321Y511616D02*
X971574Y511908D01*
X970046Y513074D01*
X968736Y514824D01*
X967862Y516866D01*
X967426Y519199D01*
Y521533D01*
X967862Y523866D01*
X968736Y525908D01*
X970046Y527657D01*
X971574Y528824D01*
X973321Y529116D01*
X975067Y528824D01*
X976596Y527657D01*
X977906Y525908D01*
X978780Y523866D01*
X979216Y521533D01*
Y519199D01*
X978780Y516866D01*
X977906Y514824D01*
X976596Y513074D01*
X975067Y511908D01*
X973321Y511616D01*
G01X987109D02*
Y529116D01*
G01Y520658D02*
X988201Y522116D01*
X989293Y522991D01*
X991039Y523282D01*
X992349Y522991D01*
X993878Y521824D01*
X994533Y520074D01*
Y511616D01*
G01X1001771D02*
Y523282D01*
G01Y520074D02*
X1002426Y521533D01*
X1003518Y522699D01*
X1005046Y523282D01*
X1006574Y522699D01*
X1007666Y521533D01*
X1008321Y520074D01*
Y511616D01*
G01Y520074D02*
X1008976Y521533D01*
X1010067Y522699D01*
X1011596Y523282D01*
X1013124Y522699D01*
X1014216Y521533D01*
X1014871Y519783D01*
Y511616D01*
G01X1026913Y505783D02*
X1029096Y508699D01*
X1030188Y511616D01*
Y523282D01*
X1029096Y526199D01*
X1026913Y529116D01*
G01X1115521D02*
X1118577Y511616D01*
X1122071Y529116D01*
X1125564Y511616D01*
X1128621Y529116D01*
G01X1136951D02*
X1142191D01*
G01X1139571D02*
Y511616D01*
G01X1136951D02*
X1142191D01*
G01X1152268D02*
Y529116D01*
X1156634D01*
X1158381Y528241D01*
X1159691Y527074D01*
X1160783Y525325D01*
X1161656Y523282D01*
X1161874Y520366D01*
X1161656Y517449D01*
X1160783Y515407D01*
X1159691Y513657D01*
X1158381Y512491D01*
X1156634Y511616D01*
X1152268D01*
G01X1174571Y529116D02*
Y511616D01*
G01X1169549Y529116D02*
X1179593D01*
G01X1187486Y511616D02*
Y529116D01*
G01X1196656D02*
Y511616D01*
G01Y520366D02*
X1187486D01*
G01X1208479Y505783D02*
X1206296Y508699D01*
X1205204Y511616D01*
Y523282D01*
X1206296Y526199D01*
X1208479Y529116D01*
G01X1220521Y511616D02*
Y523282D01*
G01Y520074D02*
X1221176Y521533D01*
X1222268Y522699D01*
X1223796Y523282D01*
X1225324Y522699D01*
X1226416Y521533D01*
X1227071Y520074D01*
Y511616D01*
G01Y520074D02*
X1227726Y521533D01*
X1228817Y522699D01*
X1230346Y523282D01*
X1231874Y522699D01*
X1232966Y521533D01*
X1233621Y519783D01*
Y511616D01*
G01X1244571Y523282D02*
Y511616D01*
G01Y527949D02*
X1244134Y528241D01*
Y528824D01*
X1244571Y529116D01*
X1245008Y528824D01*
Y528241D01*
X1244571Y527949D01*
G01X1262071Y511616D02*
Y529116D01*
G01X1276296Y513657D02*
X1277388Y512491D01*
X1278916Y511616D01*
X1280226D01*
X1281536Y512199D01*
X1282409Y513074D01*
X1282846Y514240D01*
X1282628Y515991D01*
X1281754Y516866D01*
X1277824Y518616D01*
X1276951Y520658D01*
X1277388Y522116D01*
X1278261Y522991D01*
X1279571Y523282D01*
X1280881Y522991D01*
X1282191Y522116D01*
G01X1298163Y505783D02*
X1300346Y508699D01*
X1301438Y511616D01*
Y523282D01*
X1300346Y526199D01*
X1298163Y529116D01*
G01X1152268Y411166D02*
X1153577Y409124D01*
X1155324Y407958D01*
X1157289Y407666D01*
X1159036Y407958D01*
X1160783Y409416D01*
X1161874Y411166D01*
X1162093Y412916D01*
X1161656Y414957D01*
X1160128Y416416D01*
X1158599Y416999D01*
X1156634D01*
G01X1158599D02*
X1159909Y417874D01*
X1161001Y419332D01*
X1161438Y421082D01*
X1161001Y422833D01*
X1159909Y424291D01*
X1157944Y425166D01*
X1155979Y424874D01*
X1154014Y423707D01*
G01X1174571Y407083D02*
X1174134Y407374D01*
Y407958D01*
X1174571Y408249D01*
X1175008Y407958D01*
Y407374D01*
X1174571Y407083D01*
G01X1187268Y410290D02*
X1188577Y408832D01*
X1190106Y407958D01*
X1192071Y407666D01*
X1194036Y408249D01*
X1195564Y409416D01*
X1196656Y411457D01*
X1196874Y413791D01*
X1196438Y416124D01*
X1195346Y417583D01*
X1193817Y418749D01*
X1192289Y419041D01*
X1190761Y418749D01*
X1188796Y417583D01*
X1189451Y425166D01*
X1195346D01*
G01X1205641Y407083D02*
X1213501Y425166D01*
G01X1229691Y407666D02*
Y425166D01*
X1221612Y412624D01*
X1232530D01*
G01X1244571Y407083D02*
X1244134Y407374D01*
Y407958D01*
X1244571Y408249D01*
X1245008Y407958D01*
Y407374D01*
X1244571Y407083D01*
G01X1262071Y425166D02*
X1260324Y424583D01*
X1259014Y423124D01*
X1258141Y421375D01*
X1257486Y419041D01*
X1257268Y416416D01*
X1257486Y413791D01*
X1258141Y411457D01*
X1259014Y409707D01*
X1260324Y408249D01*
X1262071Y407666D01*
X1263817Y408249D01*
X1265128Y409707D01*
X1266001Y411457D01*
X1266656Y413791D01*
X1266874Y416416D01*
X1266656Y419041D01*
X1266001Y421375D01*
X1265128Y423124D01*
X1263817Y424583D01*
X1262071Y425166D01*
G01X1159691Y373016D02*
Y390516D01*
X1151612Y377974D01*
X1162530D01*
G01X1174571Y372433D02*
X1174134Y372724D01*
Y373308D01*
X1174571Y373599D01*
X1175008Y373308D01*
Y372724D01*
X1174571Y372433D01*
G01X1192071Y390516D02*
X1190324Y389933D01*
X1189014Y388474D01*
X1188141Y386725D01*
X1187486Y384391D01*
X1187268Y381766D01*
X1187486Y379141D01*
X1188141Y376807D01*
X1189014Y375057D01*
X1190324Y373599D01*
X1192071Y373016D01*
X1193817Y373599D01*
X1195128Y375057D01*
X1196001Y376807D01*
X1196656Y379141D01*
X1196874Y381766D01*
X1196656Y384391D01*
X1196001Y386725D01*
X1195128Y388474D01*
X1193817Y389933D01*
X1192071Y390516D01*
G01X1205641Y372433D02*
X1213501Y390516D01*
G01X1227071Y373016D02*
X1228599Y373308D01*
X1230346Y374182D01*
X1231438Y375640D01*
X1231874Y377683D01*
X1231438Y379724D01*
X1230128Y381474D01*
X1228163Y382349D01*
X1225979D01*
X1224669Y382933D01*
X1223577Y384391D01*
X1223141Y386432D01*
X1223796Y388474D01*
X1225324Y389933D01*
X1227071Y390516D01*
X1228817Y389933D01*
X1230346Y388474D01*
X1231001Y386432D01*
X1230564Y384391D01*
X1229473Y382933D01*
X1228163Y382349D01*
X1225979D01*
X1224014Y381474D01*
X1222704Y379724D01*
X1222268Y377683D01*
X1222704Y375640D01*
X1223796Y374182D01*
X1225543Y373308D01*
X1227071Y373016D01*
G01X1244571Y372433D02*
X1244134Y372724D01*
Y373308D01*
X1244571Y373599D01*
X1245008Y373308D01*
Y372724D01*
X1244571Y372433D01*
G01X1262071Y390516D02*
X1260324Y389933D01*
X1259014Y388474D01*
X1258141Y386725D01*
X1257486Y384391D01*
X1257268Y381766D01*
X1257486Y379141D01*
X1258141Y376807D01*
X1259014Y375057D01*
X1260324Y373599D01*
X1262071Y373016D01*
X1263817Y373599D01*
X1265128Y375057D01*
X1266001Y376807D01*
X1266656Y379141D01*
X1266874Y381766D01*
X1266656Y384391D01*
X1266001Y386725D01*
X1265128Y388474D01*
X1263817Y389933D01*
X1262071Y390516D01*
G01X1143518Y480466D02*
X1144827Y478424D01*
X1146574Y477258D01*
X1148539Y476966D01*
X1150286Y477258D01*
X1152033Y478716D01*
X1153124Y480466D01*
X1153343Y482216D01*
X1152906Y484257D01*
X1151378Y485716D01*
X1149849Y486299D01*
X1147884D01*
G01X1149849D02*
X1151159Y487174D01*
X1152251Y488632D01*
X1152688Y490382D01*
X1152251Y492133D01*
X1151159Y493591D01*
X1149194Y494466D01*
X1147229Y494174D01*
X1145264Y493007D01*
G01X1165821Y476383D02*
X1165384Y476674D01*
Y477258D01*
X1165821Y477549D01*
X1166258Y477258D01*
Y476674D01*
X1165821Y476383D01*
G01X1182884Y476966D02*
X1183321Y480757D01*
X1183976Y483966D01*
X1184849Y486883D01*
X1185941Y490091D01*
X1187688Y494466D01*
X1178954D01*
G01X1196018Y479590D02*
X1197327Y478132D01*
X1198856Y477258D01*
X1200821Y476966D01*
X1202786Y477549D01*
X1204314Y478716D01*
X1205406Y480757D01*
X1205624Y483091D01*
X1205188Y485424D01*
X1204096Y486883D01*
X1202567Y488049D01*
X1201039Y488341D01*
X1199511Y488049D01*
X1197546Y486883D01*
X1198201Y494466D01*
X1204096D01*
G01X1214391Y476383D02*
X1222251Y494466D01*
G01X1231018Y480466D02*
X1232327Y478424D01*
X1234074Y477258D01*
X1236039Y476966D01*
X1237786Y477258D01*
X1239533Y478716D01*
X1240624Y480466D01*
X1240843Y482216D01*
X1240406Y484257D01*
X1238878Y485716D01*
X1237349Y486299D01*
X1235384D01*
G01X1237349D02*
X1238659Y487174D01*
X1239751Y488632D01*
X1240188Y490382D01*
X1239751Y492133D01*
X1238659Y493591D01*
X1236694Y494466D01*
X1234729Y494174D01*
X1232764Y493007D01*
G01X1253321Y476383D02*
X1252884Y476674D01*
Y477258D01*
X1253321Y477549D01*
X1253758Y477258D01*
Y476674D01*
X1253321Y476383D01*
G01X1266018Y479590D02*
X1267327Y478132D01*
X1268856Y477258D01*
X1270821Y476966D01*
X1272786Y477549D01*
X1274314Y478716D01*
X1275406Y480757D01*
X1275624Y483091D01*
X1275188Y485424D01*
X1274096Y486883D01*
X1272567Y488049D01*
X1271039Y488341D01*
X1269511Y488049D01*
X1267546Y486883D01*
X1268201Y494466D01*
X1274096D01*
G01X1152268Y444940D02*
X1153577Y443482D01*
X1155106Y442608D01*
X1157071Y442316D01*
X1159036Y442899D01*
X1160564Y444066D01*
X1161656Y446107D01*
X1161874Y448441D01*
X1161438Y450774D01*
X1160346Y452233D01*
X1158817Y453399D01*
X1157289Y453691D01*
X1155761Y453399D01*
X1153796Y452233D01*
X1154451Y459816D01*
X1160346D01*
G01X1174571Y441733D02*
X1174134Y442024D01*
Y442608D01*
X1174571Y442899D01*
X1175008Y442608D01*
Y442024D01*
X1174571Y441733D01*
G01X1187268Y444940D02*
X1188577Y443482D01*
X1190106Y442608D01*
X1192071Y442316D01*
X1194036Y442899D01*
X1195564Y444066D01*
X1196656Y446107D01*
X1196874Y448441D01*
X1196438Y450774D01*
X1195346Y452233D01*
X1193817Y453399D01*
X1192289Y453691D01*
X1190761Y453399D01*
X1188796Y452233D01*
X1189451Y459816D01*
X1195346D01*
G01X1205641Y441733D02*
X1213501Y459816D01*
G01X1226634Y442316D02*
X1227071Y446107D01*
X1227726Y449316D01*
X1228599Y452233D01*
X1229691Y455441D01*
X1231438Y459816D01*
X1222704D01*
G01X1244571Y441733D02*
X1244134Y442024D01*
Y442608D01*
X1244571Y442899D01*
X1245008Y442608D01*
Y442024D01*
X1244571Y441733D01*
G01X1257268Y444940D02*
X1258577Y443482D01*
X1260106Y442608D01*
X1262071Y442316D01*
X1264036Y442899D01*
X1265564Y444066D01*
X1266656Y446107D01*
X1266874Y448441D01*
X1266438Y450774D01*
X1265346Y452233D01*
X1263817Y453399D01*
X1262289Y453691D01*
X1260761Y453399D01*
X1258796Y452233D01*
X1259451Y459816D01*
X1265346D01*
G01X1406018Y407666D02*
Y425166D01*
X1410384D01*
X1412131Y424291D01*
X1413441Y423124D01*
X1414533Y421375D01*
X1415406Y419332D01*
X1415624Y416416D01*
X1415406Y413499D01*
X1414533Y411457D01*
X1413441Y409707D01*
X1412131Y408541D01*
X1410384Y407666D01*
X1406018D01*
G01X1423954D02*
Y425166D01*
X1429194D01*
X1430941Y424291D01*
X1432251Y422249D01*
X1432688Y419916D01*
X1432251Y417583D01*
X1431159Y415833D01*
X1429194Y414957D01*
X1423954D01*
G01X1406018Y373016D02*
Y390516D01*
X1410384D01*
X1412131Y389641D01*
X1413441Y388474D01*
X1414533Y386725D01*
X1415406Y384682D01*
X1415624Y381766D01*
X1415406Y378849D01*
X1414533Y376807D01*
X1413441Y375057D01*
X1412131Y373891D01*
X1410384Y373016D01*
X1406018D01*
G01X1423954D02*
Y390516D01*
X1429194D01*
X1430941Y389641D01*
X1432251Y387599D01*
X1432688Y385266D01*
X1432251Y382933D01*
X1431159Y381183D01*
X1429194Y380307D01*
X1423954D01*
G01X1406018Y476966D02*
Y494466D01*
X1410384D01*
X1412131Y493591D01*
X1413441Y492424D01*
X1414533Y490675D01*
X1415406Y488632D01*
X1415624Y485716D01*
X1415406Y482799D01*
X1414533Y480757D01*
X1413441Y479007D01*
X1412131Y477841D01*
X1410384Y476966D01*
X1406018D01*
G01X1423954D02*
Y494466D01*
X1429194D01*
X1430941Y493591D01*
X1432251Y491549D01*
X1432688Y489216D01*
X1432251Y486883D01*
X1431159Y485133D01*
X1429194Y484257D01*
X1423954D01*
G01X1406018Y442316D02*
Y459816D01*
X1410384D01*
X1412131Y458941D01*
X1413441Y457774D01*
X1414533Y456025D01*
X1415406Y453982D01*
X1415624Y451066D01*
X1415406Y448149D01*
X1414533Y446107D01*
X1413441Y444357D01*
X1412131Y443191D01*
X1410384Y442316D01*
X1406018D01*
G01X1423954D02*
Y459816D01*
X1429194D01*
X1430941Y458941D01*
X1432251Y456899D01*
X1432688Y454566D01*
X1432251Y452233D01*
X1431159Y450483D01*
X1429194Y449607D01*
X1423954D01*
G01X1393321Y529116D02*
Y511616D01*
G01X1388299Y529116D02*
X1398343D01*
G01X1410821Y511616D02*
Y519491D01*
X1406454Y529116D01*
G01X1415188D02*
X1410821Y519491D01*
G01X1423954Y511616D02*
Y529116D01*
X1429194D01*
X1430941Y528241D01*
X1432251Y526199D01*
X1432688Y523866D01*
X1432251Y521533D01*
X1431159Y519783D01*
X1429194Y518907D01*
X1423954D01*
G01X1450188Y511616D02*
X1441454D01*
Y529116D01*
X1450188D01*
G01X1446694Y520658D02*
X1441454D01*
G01X1493954Y511616D02*
Y529116D01*
X1499413D01*
X1501159Y528241D01*
X1502251Y527074D01*
X1502688Y524741D01*
X1502251Y522407D01*
X1500941Y520949D01*
X1499413Y520074D01*
X1493954D01*
G01X1499413D02*
X1502688Y511616D01*
G01X1512546Y519491D02*
X1519533D01*
X1518878Y521533D01*
X1517786Y522699D01*
X1516258Y523282D01*
X1514729Y522991D01*
X1513419Y522116D01*
X1512546Y520074D01*
X1512109Y518324D01*
Y516574D01*
X1512546Y514824D01*
X1513638Y513074D01*
X1514948Y511908D01*
X1516476Y511616D01*
X1518004Y512199D01*
X1519533Y513949D01*
G01X1532011Y511616D02*
Y526491D01*
X1532448Y527949D01*
X1533321Y528824D01*
X1534631Y529116D01*
X1535941Y528533D01*
X1536596Y527074D01*
G01X1533976Y522116D02*
X1529609D01*
G01X1550821Y511033D02*
X1550384Y511324D01*
Y511908D01*
X1550821Y512199D01*
X1551258Y511908D01*
Y511324D01*
X1550821Y511033D01*
G01X1581454Y511616D02*
Y529116D01*
X1586694D01*
X1588441Y528241D01*
X1589751Y526199D01*
X1590188Y523866D01*
X1589751Y521533D01*
X1588659Y519783D01*
X1586694Y518907D01*
X1581454D01*
G01X1603321Y511616D02*
Y529116D01*
G01X1624751Y511616D02*
Y523282D01*
G01Y521241D02*
X1623878Y522407D01*
X1622567Y522991D01*
X1621039Y523282D01*
X1619511Y522699D01*
X1618201Y521533D01*
X1617327Y519783D01*
X1616891Y517449D01*
X1617327Y515116D01*
X1618201Y513366D01*
X1619511Y512199D01*
X1621039Y511616D01*
X1622567Y511908D01*
X1623878Y512782D01*
X1624751Y513949D01*
G01X1634609Y511616D02*
Y523282D01*
G01Y520366D02*
X1635483Y521824D01*
X1636793Y522991D01*
X1638539Y523282D01*
X1640067Y522991D01*
X1641378Y521824D01*
X1642033Y519783D01*
Y511616D01*
G01X1652546Y519491D02*
X1659533D01*
X1658878Y521533D01*
X1657786Y522699D01*
X1656258Y523282D01*
X1654729Y522991D01*
X1653419Y522116D01*
X1652546Y520074D01*
X1652109Y518324D01*
Y516574D01*
X1652546Y514824D01*
X1653638Y513074D01*
X1654948Y511908D01*
X1656476Y511616D01*
X1658004Y512199D01*
X1659533Y513949D01*
G01X1537704Y425166D02*
Y407666D01*
X1546438D01*
G01X1554768Y410290D02*
X1556077Y408832D01*
X1557606Y407958D01*
X1559571Y407666D01*
X1561536Y408249D01*
X1563064Y409416D01*
X1564156Y411457D01*
X1564374Y413791D01*
X1563938Y416124D01*
X1562846Y417583D01*
X1561317Y418749D01*
X1559789Y419041D01*
X1558261Y418749D01*
X1556296Y417583D01*
X1556951Y425166D01*
X1562846D01*
G01X1573141Y407083D02*
X1581001Y425166D01*
G01X1590204D02*
Y407666D01*
X1598938D01*
G01X1611634D02*
X1612071Y411457D01*
X1612726Y414666D01*
X1613599Y417583D01*
X1614691Y420791D01*
X1616438Y425166D01*
X1607704D01*
G01X1537704Y390516D02*
Y373016D01*
X1546438D01*
G01X1554768Y375640D02*
X1556077Y374182D01*
X1557606Y373308D01*
X1559571Y373016D01*
X1561536Y373599D01*
X1563064Y374766D01*
X1564156Y376807D01*
X1564374Y379141D01*
X1563938Y381474D01*
X1562846Y382933D01*
X1561317Y384099D01*
X1559789Y384391D01*
X1558261Y384099D01*
X1556296Y382933D01*
X1556951Y390516D01*
X1562846D01*
G01X1573141Y372433D02*
X1581001Y390516D01*
G01X1590204D02*
Y373016D01*
X1598938D01*
G01X1611634D02*
X1612071Y376807D01*
X1612726Y380016D01*
X1613599Y382933D01*
X1614691Y386141D01*
X1616438Y390516D01*
X1607704D01*
G01X1537704Y494466D02*
Y476966D01*
X1546438D01*
G01X1554768Y479590D02*
X1556077Y478132D01*
X1557606Y477258D01*
X1559571Y476966D01*
X1561536Y477549D01*
X1563064Y478716D01*
X1564156Y480757D01*
X1564374Y483091D01*
X1563938Y485424D01*
X1562846Y486883D01*
X1561317Y488049D01*
X1559789Y488341D01*
X1558261Y488049D01*
X1556296Y486883D01*
X1556951Y494466D01*
X1562846D01*
G01X1573141Y476383D02*
X1581001Y494466D01*
G01X1590204D02*
Y476966D01*
X1598938D01*
G01X1611634D02*
X1612071Y480757D01*
X1612726Y483966D01*
X1613599Y486883D01*
X1614691Y490091D01*
X1616438Y494466D01*
X1607704D01*
G01X1537704Y459816D02*
Y442316D01*
X1546438D01*
G01X1554768Y444940D02*
X1556077Y443482D01*
X1557606Y442608D01*
X1559571Y442316D01*
X1561536Y442899D01*
X1563064Y444066D01*
X1564156Y446107D01*
X1564374Y448441D01*
X1563938Y450774D01*
X1562846Y452233D01*
X1561317Y453399D01*
X1559789Y453691D01*
X1558261Y453399D01*
X1556296Y452233D01*
X1556951Y459816D01*
X1562846D01*
G01X1573141Y441733D02*
X1581001Y459816D01*
G01X1590204D02*
Y442316D01*
X1598938D01*
G01X1611634D02*
X1612071Y446107D01*
X1612726Y449316D01*
X1613599Y452233D01*
X1614691Y455441D01*
X1616438Y459816D01*
X1607704D01*
G01X1773621Y488632D02*
Y476966D01*
G01Y493299D02*
X1773184Y493591D01*
Y494174D01*
X1773621Y494466D01*
X1774058Y494174D01*
Y493591D01*
X1773621Y493299D01*
G01X1787846Y479007D02*
X1788938Y477841D01*
X1790466Y476966D01*
X1791776D01*
X1793086Y477549D01*
X1793959Y478424D01*
X1794396Y479590D01*
X1794178Y481341D01*
X1793304Y482216D01*
X1789374Y483966D01*
X1788501Y486008D01*
X1788938Y487466D01*
X1789811Y488341D01*
X1791121Y488632D01*
X1792431Y488341D01*
X1793741Y487466D01*
G01X1821099Y476966D02*
Y494466D01*
X1831143Y476966D01*
Y494466D01*
G01X1843621Y476966D02*
X1841874Y477258D01*
X1840346Y478424D01*
X1839036Y480174D01*
X1838162Y482216D01*
X1837726Y484549D01*
Y486883D01*
X1838162Y489216D01*
X1839036Y491258D01*
X1840346Y493007D01*
X1841874Y494174D01*
X1843621Y494466D01*
X1845367Y494174D01*
X1846896Y493007D01*
X1848206Y491258D01*
X1849080Y489216D01*
X1849516Y486883D01*
Y484549D01*
X1849080Y482216D01*
X1848206Y480174D01*
X1846896Y478424D01*
X1845367Y477258D01*
X1843621Y476966D01*
G01X1861121Y494466D02*
Y476966D01*
G01X1856099Y494466D02*
X1866143D01*
G01X1892409Y488632D02*
Y480466D01*
X1893283Y478424D01*
X1894593Y477258D01*
X1896121Y476966D01*
X1897649Y477258D01*
X1898959Y478424D01*
X1899833Y480466D01*
G01Y476966D02*
Y488632D01*
G01X1910346Y479007D02*
X1911438Y477841D01*
X1912966Y476966D01*
X1914276D01*
X1915586Y477549D01*
X1916459Y478424D01*
X1916896Y479590D01*
X1916678Y481341D01*
X1915804Y482216D01*
X1911874Y483966D01*
X1911001Y486008D01*
X1911438Y487466D01*
X1912311Y488341D01*
X1913621Y488632D01*
X1914931Y488341D01*
X1916241Y487466D01*
G01X1927846Y484841D02*
X1934833D01*
X1934178Y486883D01*
X1933086Y488049D01*
X1931558Y488632D01*
X1930029Y488341D01*
X1928719Y487466D01*
X1927846Y485424D01*
X1927409Y483674D01*
Y481924D01*
X1927846Y480174D01*
X1928938Y478424D01*
X1930248Y477258D01*
X1931776Y476966D01*
X1933304Y477549D01*
X1934833Y479299D01*
G01X1952551Y494466D02*
Y476966D01*
G01Y479590D02*
X1951678Y478132D01*
X1950367Y477258D01*
X1948839Y476966D01*
X1947093Y477549D01*
X1945783Y479007D01*
X1944909Y480757D01*
X1944691Y482799D01*
X1944909Y484841D01*
X1945783Y486591D01*
X1947093Y488049D01*
X1948839Y488632D01*
X1950367Y488341D01*
X1951459Y487757D01*
X1952551Y486591D01*
G01X1698818Y511033D02*
X1708424Y523866D01*
G01X1703621Y526199D02*
Y508699D01*
G01X1708424Y511033D02*
X1698818Y523866D01*
G01X1697071Y517449D02*
X1710171D01*
G01X1735783D02*
X1741459D01*
G01X1768818Y511616D02*
Y529116D01*
X1773184D01*
X1774931Y528241D01*
X1776241Y527074D01*
X1777333Y525325D01*
X1778206Y523282D01*
X1778424Y520366D01*
X1778206Y517449D01*
X1777333Y515407D01*
X1776241Y513657D01*
X1774931Y512491D01*
X1773184Y511616D01*
X1768818D01*
G01X1787846Y519491D02*
X1794833D01*
X1794178Y521533D01*
X1793086Y522699D01*
X1791558Y523282D01*
X1790029Y522991D01*
X1788719Y522116D01*
X1787846Y520074D01*
X1787409Y518324D01*
Y516574D01*
X1787846Y514824D01*
X1788938Y513074D01*
X1790248Y511908D01*
X1791776Y511616D01*
X1793304Y512199D01*
X1794833Y513949D01*
G01X1804909Y511616D02*
Y523282D01*
G01Y520366D02*
X1805783Y521824D01*
X1807093Y522991D01*
X1808839Y523282D01*
X1810367Y522991D01*
X1811678Y521824D01*
X1812333Y519783D01*
Y511616D01*
G01X1826121D02*
X1824811Y511908D01*
X1823501Y513074D01*
X1822627Y515116D01*
X1822191Y517449D01*
X1822627Y519783D01*
X1823501Y521824D01*
X1824811Y522991D01*
X1826121Y523282D01*
X1827431Y522991D01*
X1828741Y521824D01*
X1829614Y519783D01*
X1829833Y517449D01*
X1829614Y515116D01*
X1828741Y513074D01*
X1827431Y511908D01*
X1826121Y511616D01*
G01X1843621Y529116D02*
Y511616D01*
G01X1840564Y523282D02*
X1846678D01*
G01X1857846Y519491D02*
X1864833D01*
X1864178Y521533D01*
X1863086Y522699D01*
X1861558Y523282D01*
X1860029Y522991D01*
X1858719Y522116D01*
X1857846Y520074D01*
X1857409Y518324D01*
Y516574D01*
X1857846Y514824D01*
X1858938Y513074D01*
X1860248Y511908D01*
X1861776Y511616D01*
X1863304Y512199D01*
X1864833Y513949D01*
G01X1875346Y513657D02*
X1876438Y512491D01*
X1877966Y511616D01*
X1879276D01*
X1880586Y512199D01*
X1881459Y513074D01*
X1881896Y514240D01*
X1881678Y515991D01*
X1880804Y516866D01*
X1876874Y518616D01*
X1876001Y520658D01*
X1876438Y522116D01*
X1877311Y522991D01*
X1878621Y523282D01*
X1879931Y522991D01*
X1881241Y522116D01*
G01X1913621Y529116D02*
Y511616D01*
G01X1910564Y523282D02*
X1916678D01*
G01X1927409Y511616D02*
Y529116D01*
G01Y520658D02*
X1928501Y522116D01*
X1929593Y522991D01*
X1931339Y523282D01*
X1932649Y522991D01*
X1934178Y521824D01*
X1934833Y520074D01*
Y511616D01*
G01X1952551D02*
Y523282D01*
G01Y521241D02*
X1951678Y522407D01*
X1950367Y522991D01*
X1948839Y523282D01*
X1947311Y522699D01*
X1946001Y521533D01*
X1945127Y519783D01*
X1944691Y517449D01*
X1945127Y515116D01*
X1946001Y513366D01*
X1947311Y512199D01*
X1948839Y511616D01*
X1950367Y511908D01*
X1951678Y512782D01*
X1952551Y513949D01*
G01X1966121Y529116D02*
Y511616D01*
G01X1963064Y523282D02*
X1969178D01*
G01X2001121Y529116D02*
Y511616D01*
G01X1998064Y523282D02*
X2004178D01*
G01X2014909Y511616D02*
Y529116D01*
G01Y520658D02*
X2016001Y522116D01*
X2017093Y522991D01*
X2018839Y523282D01*
X2020149Y522991D01*
X2021678Y521824D01*
X2022333Y520074D01*
Y511616D01*
G01X2036121Y523282D02*
Y511616D01*
G01Y527949D02*
X2035684Y528241D01*
Y528824D01*
X2036121Y529116D01*
X2036558Y528824D01*
Y528241D01*
X2036121Y527949D01*
G01X2050346Y513657D02*
X2051438Y512491D01*
X2052966Y511616D01*
X2054276D01*
X2055586Y512199D01*
X2056459Y513074D01*
X2056896Y514240D01*
X2056678Y515991D01*
X2055804Y516866D01*
X2051874Y518616D01*
X2051001Y520658D01*
X2051438Y522116D01*
X2052311Y522991D01*
X2053621Y523282D01*
X2054931Y522991D01*
X2056241Y522116D01*
G01X2086001Y529116D02*
X2091241D01*
G01X2088621D02*
Y511616D01*
G01X2086001D02*
X2091241D01*
G01X2099571D02*
Y523282D01*
G01Y520074D02*
X2100226Y521533D01*
X2101318Y522699D01*
X2102846Y523282D01*
X2104374Y522699D01*
X2105466Y521533D01*
X2106121Y520074D01*
Y511616D01*
G01Y520074D02*
X2106776Y521533D01*
X2107867Y522699D01*
X2109396Y523282D01*
X2110924Y522699D01*
X2112016Y521533D01*
X2112671Y519783D01*
Y511616D01*
G01X2119691Y505783D02*
Y523282D01*
G01Y520658D02*
X2120783Y522116D01*
X2121874Y522991D01*
X2123621Y523282D01*
X2125149Y522991D01*
X2126678Y521533D01*
X2127333Y519491D01*
X2127551Y517449D01*
X2127333Y515407D01*
X2126678Y513366D01*
X2125367Y512199D01*
X2123621Y511616D01*
X2122093Y511908D01*
X2120564Y512782D01*
X2119691Y513949D01*
G01X2137846Y519491D02*
X2144833D01*
X2144178Y521533D01*
X2143086Y522699D01*
X2141558Y523282D01*
X2140029Y522991D01*
X2138719Y522116D01*
X2137846Y520074D01*
X2137409Y518324D01*
Y516574D01*
X2137846Y514824D01*
X2138938Y513074D01*
X2140248Y511908D01*
X2141776Y511616D01*
X2143304Y512199D01*
X2144833Y513949D01*
G01X2162551Y529116D02*
Y511616D01*
G01Y514240D02*
X2161678Y512782D01*
X2160367Y511908D01*
X2158839Y511616D01*
X2157093Y512199D01*
X2155783Y513657D01*
X2154909Y515407D01*
X2154691Y517449D01*
X2154909Y519491D01*
X2155783Y521241D01*
X2157093Y522699D01*
X2158839Y523282D01*
X2160367Y522991D01*
X2161459Y522407D01*
X2162551Y521241D01*
G01X2180051Y511616D02*
Y523282D01*
G01Y521241D02*
X2179178Y522407D01*
X2177867Y522991D01*
X2176339Y523282D01*
X2174811Y522699D01*
X2173501Y521533D01*
X2172627Y519783D01*
X2172191Y517449D01*
X2172627Y515116D01*
X2173501Y513366D01*
X2174811Y512199D01*
X2176339Y511616D01*
X2177867Y511908D01*
X2179178Y512782D01*
X2180051Y513949D01*
G01X2189909Y511616D02*
Y523282D01*
G01Y520366D02*
X2190783Y521824D01*
X2192093Y522991D01*
X2193839Y523282D01*
X2195367Y522991D01*
X2196678Y521824D01*
X2197333Y519783D01*
Y511616D01*
G01X2214614Y521824D02*
X2213086Y522991D01*
X2211776Y523282D01*
X2210029Y522699D01*
X2208719Y521533D01*
X2207846Y519491D01*
X2207627Y517449D01*
X2207846Y515407D01*
X2208719Y513657D01*
X2210029Y512199D01*
X2211776Y511616D01*
X2213304Y512199D01*
X2214614Y513366D01*
G01X2225346Y519491D02*
X2232333D01*
X2231678Y521533D01*
X2230586Y522699D01*
X2229058Y523282D01*
X2227529Y522991D01*
X2226219Y522116D01*
X2225346Y520074D01*
X2224909Y518324D01*
Y516574D01*
X2225346Y514824D01*
X2226438Y513074D01*
X2227748Y511908D01*
X2229276Y511616D01*
X2230804Y512199D01*
X2232333Y513949D01*
G01X20103Y-86244D02*
G03I-4291J0D01*
G01X0Y-87362D02*
G03X15000Y-102362I15000J0D01*
G01X0Y-11811D02*
Y-87362D01*
G01X3937Y-7874D02*
G03X0Y-11811I0J-3937D01*
G01X15748Y-7874D02*
X3937D01*
G01X0Y7874D02*
G03X7874Y0I7874J0D01*
G01X818897D02*
X7874D01*
G01X0Y7874D02*
Y562992D01*
G01X7874Y570866D02*
G03X0Y562992I0J-7874D01*
G01X7874Y570866D02*
X326781D01*
G01X312004Y-102362D02*
X15000D01*
G01X46456Y0D02*
G03Y-7874I0J-3937D01*
G01X15748D02*
G03Y0I0J3937D01*
G01X287400Y-7874D02*
X46456D01*
G01X40452Y499724D02*
G03I-3051J0D01*
G01X41535Y535157D02*
G03I-4134J0D01*
G01X44685Y517441D02*
G03I-7284J0D01*
G01X121082Y39055D02*
G03I-5019J0D01*
G01X120807Y14567D02*
G03I-4744J0D01*
G01X319878Y-102362D02*
G03X312004I-3937J0D01*
G01X811771D02*
X319878D01*
G01X326770Y0D02*
G03Y-7874I0J-3937D01*
G01X287400D02*
G03Y0I0J3937D01*
G01X302165Y531496D02*
G03I-6890J0D01*
G01X597707Y-7874D02*
X326770D01*
G01X379921Y156220D02*
G03I-5906J0D01*
G01X342529Y530315D02*
G03X334655I-3937J0D01*
G01X342529Y520720D02*
G03X352474Y509057I11811J0D01*
G01X334655Y520720D02*
G03X351230Y501282I19685J0D01*
G01X384484Y503937D02*
X352475Y509057D01*
G01X383858Y496063D02*
X351231Y501282D01*
G01X442287Y503937D02*
X384484D01*
G01X442913Y496063D02*
X383858D01*
G01X342529Y530315D02*
Y520720D01*
G01X334655Y562992D02*
Y520720D01*
G01X346466Y570866D02*
G03X342529Y566929I0J-3937D01*
G01X334655Y555512D02*
G03X342529I3937J0D01*
G01X346466Y570866D02*
X480325D01*
G01X334655Y562992D02*
G03X326781Y570866I-7874J0D01*
G01X342529Y566929D02*
Y555512D01*
G01X415943Y539991D02*
G03I-4291J0D01*
G01X474316Y509060D02*
X442287Y503937D01*
G01X475560Y501285D02*
X442913Y496063D01*
G01X492136Y530315D02*
G03X484262I-3937J0D01*
G01X474316Y509060D02*
G03X484262Y520723I-1865J11663D01*
G01X475560Y501285D02*
G03X492136Y520723I-3109J19438D01*
G01X484262Y530315D02*
Y520723D01*
G01X492136Y562992D02*
Y520723D01*
G01X484262Y566929D02*
G03X480325Y570866I-3937J0D01*
G01X484262Y555512D02*
G03X492136I3937J0D01*
G01X500010Y570866D02*
G03X492136Y562992I0J-7874D01*
G01X500010Y570866D02*
X818897D01*
G01X484262Y566929D02*
Y555512D01*
G01X537401Y371299D02*
G03I-5905J0D01*
G01X538386Y531496D02*
G03I-6890J0D01*
G01X628416Y0D02*
G03Y-7874I0J-3937D01*
G01X597707D02*
G03Y0I0J3937D01*
G01X780315Y-7874D02*
X628416D01*
G01X602362Y116141D02*
G03I-5906J0D01*
G01X817003Y-86834D02*
G03I-4292J0D01*
G01X811771Y-102362D02*
G03X826771Y-87362I0J15000D01*
G01X811023Y0D02*
G03Y-7874I0J-3937D01*
G01X780315D02*
G03Y0I0J3937D01*
G01X822834Y-7874D02*
X811023D01*
G01X818897Y0D02*
G03X826771Y7874I0J7874D01*
G01X818897Y0D02*
X807086D01*
G01X787401Y198819D02*
G03I-5905J0D01*
G01X792421Y499724D02*
G03I-3051J0D01*
G01X793504Y535157D02*
G03I-4134J0D01*
G01X796653Y517441D02*
G03I-7283J0D01*
G01X826771Y562992D02*
G03X818897Y570866I-7874J0D01*
G01X826771Y-11811D02*
Y-87362D01*
G01Y-11811D02*
G03X822834Y-7874I-3937J0D01*
G01X826771Y562992D02*
Y7874D01*
G54D13*
G01X697388Y42059D02*
X684555Y61814D01*
G01X697388Y42059D02*
X684555Y61814D01*
G01X692188Y47676D02*
X691289Y49060D01*
G01X697388Y42059D02*
X684555Y61814D01*
G01X696166Y41553D02*
X693849Y45119D01*
G01X697388Y42059D02*
X684555Y61814D01*
G01X700413Y21571D02*
X696166Y41552D01*
G01X697388Y42059D02*
X684555Y61814D01*
G01X692188Y47676D02*
X691289Y49060D01*
G01X696166Y41553D02*
X693849Y45119D01*
G01X700413Y21571D02*
X696166Y41552D01*
G01X696690Y92058D02*
X695465D01*
G01X696690Y93358D02*
X695465D01*
G01X697774Y90974D02*
G03X696690Y92058I-1084J0D01*
G01X699074Y90974D02*
G03X696690Y93358I-2384J0D01*
G01D02*
X695465D01*
G01X696690Y92058D02*
X695465D01*
G01X699074Y90974D02*
G03X696690Y93358I-2384J0D01*
G01X697774Y90974D02*
G03X696690Y92058I-1084J0D01*
G01X688788Y92094D02*
X687379D01*
G01X688788Y93394D02*
X687379D01*
G01X689847Y91035D02*
G03X688788Y92094I-1059J0D01*
G01X691147Y91035D02*
G03X688788Y93394I-2359J0D01*
G01X689847Y87002D02*
Y91035D01*
G01X691147Y87541D02*
Y91035D01*
G01X693013Y83836D02*
X689847Y87002D01*
G01X694313Y84375D02*
X691147Y87541D01*
G01X693013Y80437D02*
Y83836D01*
G01X694313Y80976D02*
Y84375D01*
G01X698296Y75154D02*
X693013Y80437D01*
G01X699127Y76162D02*
X694313Y80976D01*
G01X688788Y93394D02*
X687379D01*
G01X688788Y92094D02*
X687379D01*
G01X691147Y91035D02*
G03X688788Y93394I-2359J0D01*
G01X689847Y91035D02*
G03X688788Y92094I-1059J0D01*
G01X691147Y87541D02*
Y91035D01*
G01X689847Y87002D02*
Y91035D01*
G01X694313Y84375D02*
X691147Y87541D01*
G01X693013Y83836D02*
X689847Y87002D01*
G01X694313Y80976D02*
Y84375D01*
G01X693013Y80437D02*
Y83836D01*
G01X699127Y76162D02*
X694313Y80976D01*
G01X698296Y75154D02*
X693013Y80437D01*
G01X680540Y92096D02*
X679325D01*
G01X680540Y93396D02*
X679325D01*
G01X681861Y90775D02*
G03X680540Y92096I-1321J0D01*
G01X683161Y90775D02*
G03X680540Y93396I-2621J0D01*
G01X681861Y87483D02*
Y90775D01*
G01X683161Y87921D02*
Y90775D01*
G01X685309Y82941D02*
X681861Y87483D01*
G01X686491Y83534D02*
X683161Y87921D01*
G01X686153Y80043D02*
X685309Y82941D01*
G01X686980Y81854D02*
X686491Y83534D01*
G01X687349Y80586D02*
X686980Y81854D01*
G01X687312Y78229D02*
X686153Y80043D01*
G01X688267Y79151D02*
X687349Y80586D01*
G01X689829Y76492D02*
X687312Y78229D01*
G01X701975Y69692D02*
X688267Y79151D01*
G01X692339Y74760D02*
X691365Y74582D01*
G01X701975Y69692D02*
X688267Y79151D01*
G01X693697Y73823D02*
X692339Y74760D01*
G01X701975Y69692D02*
X688267Y79151D01*
G01X696208Y72091D02*
X695234Y71912D01*
G01X701975Y69692D02*
X688267Y79151D01*
G01X697566Y71154D02*
X696208Y72091D01*
G01X701975Y69692D02*
X688267Y79151D01*
G01X701975Y69692D02*
X688267Y79151D01*
G01X701975Y69692D02*
X688267Y79151D01*
G01X680540Y93396D02*
X679325D01*
G01X680540Y92096D02*
X679325D01*
G01X683161Y90775D02*
G03X680540Y93396I-2621J0D01*
G01X681861Y90775D02*
G03X680540Y92096I-1321J0D01*
G01X683161Y87921D02*
Y90775D01*
G01X681861Y87483D02*
Y90775D01*
G01X686491Y83534D02*
X683161Y87921D01*
G01X685309Y82941D02*
X681861Y87483D01*
G01X686980Y81854D02*
X686491Y83534D01*
G01X686153Y80043D02*
X685309Y82941D01*
G01X687349Y80586D02*
X686980Y81854D01*
G01X686153Y80043D02*
X685309Y82941D01*
G01X688267Y79151D02*
X687349Y80586D01*
G01X687312Y78229D02*
X686153Y80043D01*
G01X701975Y69692D02*
X688267Y79151D01*
G01X689829Y76492D02*
X687312Y78229D01*
G01X692339Y74760D02*
X691365Y74582D01*
G01X693697Y73823D02*
X692339Y74760D01*
G01X696208Y72091D02*
X695234Y71912D01*
G01X697566Y71154D02*
X696208Y72091D01*
G01X672293Y92105D02*
X671246D01*
G01X672293Y93405D02*
X671246D01*
G01X673788Y90610D02*
G03X672293Y92105I-1495J0D01*
G01X675088Y90610D02*
G03X672293Y93405I-2795J0D01*
G01X673788Y87946D02*
Y90610D01*
G01X675088Y88339D02*
Y90610D01*
G01X681444Y76410D02*
X673788Y87946D01*
G01X682385Y77344D02*
X675088Y88339D01*
G01X687413Y72384D02*
X681444Y76410D01*
G01X703087Y63381D02*
X682385Y77344D01*
G01X689941Y70679D02*
X688969Y70490D01*
G01X703087Y63381D02*
X682385Y77344D01*
G01X691309Y69756D02*
X689941Y70679D01*
G01X703087Y63381D02*
X682385Y77344D01*
G01X693838Y68051D02*
X692866Y67862D01*
G01X703087Y63381D02*
X682385Y77344D01*
G01X695206Y67128D02*
X693838Y68051D01*
G01X703087Y63381D02*
X682385Y77344D01*
G01X697734Y65423D02*
X696762Y65234D01*
G01X703087Y63381D02*
X682385Y77344D01*
G01X703087Y63381D02*
X682385Y77344D01*
G01X672293Y93405D02*
X671246D01*
G01X672293Y92105D02*
X671246D01*
G01X675088Y90610D02*
G03X672293Y93405I-2795J0D01*
G01X673788Y90610D02*
G03X672293Y92105I-1495J0D01*
G01X675088Y88339D02*
Y90610D01*
G01X673788Y87946D02*
Y90610D01*
G01X682385Y77344D02*
X675088Y88339D01*
G01X681444Y76410D02*
X673788Y87946D01*
G01X703087Y63381D02*
X682385Y77344D01*
G01X687413Y72384D02*
X681444Y76410D01*
G01X689941Y70679D02*
X688969Y70490D01*
G01X691309Y69756D02*
X689941Y70679D01*
G01X693838Y68051D02*
X692866Y67862D01*
G01X695206Y67128D02*
X693838Y68051D01*
G01X697734Y65423D02*
X696762Y65234D01*
G01X664411Y92139D02*
X663147D01*
G01X664411Y93439D02*
X663147D01*
G01X665366Y91184D02*
G03X664411Y92139I-955J0D01*
G01X666666Y91184D02*
G03X664411Y93439I-2255J0D01*
G01X665366Y88999D02*
Y91184D01*
G01X666666Y88660D02*
Y91184D01*
G01X662886Y84561D02*
X665366Y88999D01*
G01X664118Y84098D02*
X666666Y88660D01*
G01X662459Y82552D02*
X662886Y84561D01*
G01X664036Y83712D02*
X664118Y84098D01*
G01X663788Y82551D02*
X664036Y83712D01*
G01X663043Y79773D02*
X662459Y82552D01*
G01X664266Y80278D02*
X663788Y82551D01*
G01X664064Y78199D02*
X663043Y79773D01*
G01X664938Y79242D02*
X664266Y80278D01*
G01X678428Y72135D02*
X664064Y78199D01*
G01X679051Y73284D02*
X664938Y79242D01*
G01X680213Y70932D02*
X678428Y72135D01*
G01X698845Y59936D02*
X679051Y73284D01*
G01X680897Y70470D02*
X680213Y70932D01*
G01X698845Y59936D02*
X679051Y73284D01*
G01X683426Y68765D02*
X682454Y68576D01*
G01X698845Y59936D02*
X679051Y73284D01*
G01X684794Y67842D02*
X683426Y68765D01*
G01X698845Y59936D02*
X679051Y73284D01*
G01X687323Y66137D02*
X686351Y65948D01*
G01X698845Y59936D02*
X679051Y73284D01*
G01X688691Y65214D02*
X687323Y66137D01*
G01X698845Y59936D02*
X679051Y73284D01*
G01X691220Y63509D02*
X690248Y63320D01*
G01X698845Y59936D02*
X679051Y73284D01*
G01X698337Y58709D02*
X691220Y63509D01*
G01X698845Y59936D02*
X679051Y73284D01*
G01X664411Y93439D02*
X663147D01*
G01X664411Y92139D02*
X663147D01*
G01X666666Y91184D02*
G03X664411Y93439I-2255J0D01*
G01X665366Y91184D02*
G03X664411Y92139I-955J0D01*
G01X666666Y88660D02*
Y91184D01*
G01X665366Y88999D02*
Y91184D01*
G01X664118Y84098D02*
X666666Y88660D01*
G01X662886Y84561D02*
X665366Y88999D01*
G01X664036Y83712D02*
X664118Y84098D01*
G01X662459Y82552D02*
X662886Y84561D01*
G01X663788Y82551D02*
X664036Y83712D01*
G01X662459Y82552D02*
X662886Y84561D01*
G01X664266Y80278D02*
X663788Y82551D01*
G01X663043Y79773D02*
X662459Y82552D01*
G01X664938Y79242D02*
X664266Y80278D01*
G01X664064Y78199D02*
X663043Y79773D01*
G01X679051Y73284D02*
X664938Y79242D01*
G01X678428Y72135D02*
X664064Y78199D01*
G01X698845Y59936D02*
X679051Y73284D01*
G01X680213Y70932D02*
X678428Y72135D01*
G01X680897Y70470D02*
X680213Y70932D01*
G01X683426Y68765D02*
X682454Y68576D01*
G01X684794Y67842D02*
X683426Y68765D01*
G01X687323Y66137D02*
X686351Y65948D01*
G01X688691Y65214D02*
X687323Y66137D01*
G01X691220Y63509D02*
X690248Y63320D01*
G01X698337Y58709D02*
X691220Y63509D01*
G01X656203Y92308D02*
X655137D01*
G01X656203Y93608D02*
X655137D01*
G01X657581Y90930D02*
G03X656203Y92308I-1378J0D01*
G01X658881Y90930D02*
G03X656203Y93608I-2678J0D01*
G01X657581Y90102D02*
Y90930D01*
G01X658881Y89952D02*
Y90930D01*
G01X657123Y88141D02*
X657581Y90102D01*
G01X658326Y87574D02*
X658881Y89952D01*
G01X653627Y83559D02*
X657123Y88141D01*
G01X656587Y85295D02*
X658326Y87574D01*
G01X654849Y83016D02*
X656587Y85295D01*
G01X653368Y82167D02*
X653627Y83559D01*
G01X654489Y81084D02*
X654849Y83016D01*
G01X653301Y81806D02*
X653368Y82167D01*
G01X654489Y81084D02*
X654849Y83016D01*
G01X653143Y80960D02*
X653301Y81806D01*
G01X654489Y81084D02*
X654849Y83016D01*
G01X653455Y80151D02*
X653143Y80960D01*
G01X654553Y80919D02*
X654489Y81084D01*
G01X654742Y80430D02*
X654553Y80919D01*
G01X653514Y79999D02*
X653455Y80151D01*
G01X654742Y80430D02*
X654553Y80919D01*
G01X653571Y79849D02*
X653514Y79999D01*
G01X654742Y80430D02*
X654553Y80919D01*
G01X653864Y79087D02*
X653571Y79849D01*
G01X654842Y80166D02*
X654773Y80349D01*
G01X655078Y79554D02*
X654842Y80166D01*
G01X655691Y77963D02*
X655078Y79554D01*
G01X654696Y76927D02*
X653864Y79087D01*
G01X655078Y79554D02*
X654842Y80166D01*
G01X655691Y77963D02*
X655078Y79554D01*
G01X665026Y73415D02*
X654696Y76927D01*
G01X665609Y74590D02*
X655691Y77963D01*
G01X683608Y60883D02*
X665026Y73415D01*
G01X684555Y61814D02*
X665609Y74590D01*
G01X687067Y55558D02*
X683608Y60883D01*
G01X689628Y51617D02*
X688729Y53001D01*
G01X656203Y93608D02*
X655137D01*
G01X656203Y92308D02*
X655137D01*
G01X658881Y90930D02*
G03X656203Y93608I-2678J0D01*
G01X657581Y90930D02*
G03X656203Y92308I-1378J0D01*
G01X658881Y89952D02*
Y90930D01*
G01X657581Y90102D02*
Y90930D01*
G01X658326Y87574D02*
X658881Y89952D01*
G01X657123Y88141D02*
X657581Y90102D01*
G01X656587Y85295D02*
X658326Y87574D01*
G01X653627Y83559D02*
X657123Y88141D01*
G01X654849Y83016D02*
X656587Y85295D01*
G01X653627Y83559D02*
X657123Y88141D01*
G01X654489Y81084D02*
X654849Y83016D01*
G01X653368Y82167D02*
X653627Y83559D01*
G01X653301Y81806D02*
X653368Y82167D01*
G01X653143Y80960D02*
X653301Y81806D01*
G01X654553Y80919D02*
X654489Y81084D01*
G01X653455Y80151D02*
X653143Y80960D01*
G01X654742Y80430D02*
X654553Y80919D01*
G01X653455Y80151D02*
X653143Y80960D01*
G01X653514Y79999D02*
X653455Y80151D01*
G01X653571Y79849D02*
X653514Y79999D01*
G01X654842Y80166D02*
X654773Y80349D01*
G01X653864Y79087D02*
X653571Y79849D01*
G01X655078Y79554D02*
X654842Y80166D01*
G01X653864Y79087D02*
X653571Y79849D01*
G01X654696Y76927D02*
X653864Y79087D01*
G01X655691Y77963D02*
X655078Y79554D01*
G01X653864Y79087D02*
X653571Y79849D01*
G01X654696Y76927D02*
X653864Y79087D01*
G01X665609Y74590D02*
X655691Y77963D01*
G01X665026Y73415D02*
X654696Y76927D01*
G01X684555Y61814D02*
X665609Y74590D01*
G01X683608Y60883D02*
X665026Y73415D01*
G01X687067Y55558D02*
X683608Y60883D01*
G01X689628Y51617D02*
X688729Y53001D01*
G01X754074Y14762D02*
Y51432D01*
G01X755374Y14762D02*
Y51569D01*
G01X756493Y12343D02*
G02X754074Y14762I0J2419D01*
G01X756493Y13643D02*
G02X755374Y14762I0J1119D01*
G01X757611Y12343D02*
X756493D01*
G01X757612Y13643D02*
X756493D01*
G01X755374Y14762D02*
Y51569D01*
G01X754074Y14762D02*
Y51432D01*
G01X756493Y13643D02*
G02X755374Y14762I0J1119D01*
G01X756493Y12343D02*
G02X754074Y14762I0J2419D01*
G01X757612Y13643D02*
X756493D01*
G01X757611Y12343D02*
X756493D01*
G01X746988Y46840D02*
X745635Y53213D01*
G01X748288Y46977D02*
X746857Y53719D01*
G01X746988Y19286D02*
Y46840D01*
G01X748288Y19286D02*
Y46977D01*
G01X749207Y17067D02*
G02X746988Y19286I0J2219D01*
G01X749207Y18367D02*
G02X748288Y19286I0J919D01*
G01X750525Y17067D02*
X749207D01*
G01X750525Y18367D02*
X749207D01*
G01X748288Y46977D02*
X746857Y53719D01*
G01X746988Y46840D02*
X745635Y53213D01*
G01X748288Y19286D02*
Y46977D01*
G01X746988Y19286D02*
Y46840D01*
G01X749207Y18367D02*
G02X748288Y19286I0J919D01*
G01X749207Y17067D02*
G02X746988Y19286I0J2219D01*
G01X750525Y18367D02*
X749207D01*
G01X750525Y17067D02*
X749207D01*
G01X739901Y14762D02*
Y51579D01*
G01X741201Y14762D02*
Y51716D01*
G01X742320Y12343D02*
G02X739901Y14762I0J2419D01*
G01X742320Y13643D02*
G02X741201Y14762I0J1119D01*
G01X743438Y12343D02*
X742320D01*
G01X743439Y13643D02*
X742320D01*
G01X741201Y14762D02*
Y51716D01*
G01X739901Y14762D02*
Y51579D01*
G01X742320Y13643D02*
G02X741201Y14762I0J1119D01*
G01X742320Y12343D02*
G02X739901Y14762I0J2419D01*
G01X743439Y13643D02*
X742320D01*
G01X743438Y12343D02*
X742320D01*
G01X732814Y47440D02*
X731834Y52481D01*
G01X734114Y47566D02*
X733060Y52989D01*
G01X732814Y19286D02*
Y47440D01*
G01X734114Y19286D02*
Y47566D01*
G01X735033Y17067D02*
G02X732814Y19286I0J2219D01*
G01X735033Y18367D02*
G02X734114Y19286I0J919D01*
G01X736351Y17067D02*
X735033D01*
G01X736351Y18367D02*
X735033D01*
G01X734114Y47566D02*
X733060Y52989D01*
G01X732814Y47440D02*
X731834Y52481D01*
G01X734114Y19286D02*
Y47566D01*
G01X732814Y19286D02*
Y47440D01*
G01X735033Y18367D02*
G02X734114Y19286I0J919D01*
G01X735033Y17067D02*
G02X732814Y19286I0J2219D01*
G01X736351Y18367D02*
X735033D01*
G01X736351Y17067D02*
X735033D01*
G01X725727Y14763D02*
Y53047D01*
G01X727027Y14763D02*
Y53172D01*
G01X728147Y12343D02*
G02X725727Y14763I0J2420D01*
G01X728147Y13643D02*
G02X727027Y14763I0J1120D01*
G01X729265Y12343D02*
X728147D01*
G01X729266Y13643D02*
X728147D01*
G01X727027Y14763D02*
Y53172D01*
G01X725727Y14763D02*
Y53047D01*
G01X728147Y13643D02*
G02X727027Y14763I0J1120D01*
G01X728147Y12343D02*
G02X725727Y14763I0J2420D01*
G01X729266Y13643D02*
X728147D01*
G01X729265Y12343D02*
X728147D01*
G01X718641Y49250D02*
X717720Y52216D01*
G01X719941Y49448D02*
X718905Y52784D01*
G01X718641Y19286D02*
Y49250D01*
G01X719941Y19286D02*
Y49448D01*
G01X720860Y17067D02*
G02X718641Y19286I0J2219D01*
G01X720860Y18367D02*
G02X719941Y19286I0J919D01*
G01X722178Y17067D02*
X720860D01*
G01X722178Y18367D02*
X720860D01*
G01X719941Y49448D02*
X718905Y52784D01*
G01X718641Y49250D02*
X717720Y52216D01*
G01X719941Y19286D02*
Y49448D01*
G01X718641Y19286D02*
Y49250D01*
G01X720860Y18367D02*
G02X719941Y19286I0J919D01*
G01X720860Y17067D02*
G02X718641Y19286I0J2219D01*
G01X722178Y18367D02*
X720860D01*
G01X722178Y17067D02*
X720860D01*
G01X711554Y14763D02*
Y51984D01*
G01X712854Y14763D02*
Y52121D01*
G01X713974Y12343D02*
G02X711554Y14763I0J2420D01*
G01X713974Y13643D02*
G02X712854Y14763I0J1120D01*
G01X715092Y12343D02*
X713974D01*
G01X715093Y13643D02*
X713974D01*
G01X712854Y14763D02*
Y52121D01*
G01X711554Y14763D02*
Y51984D01*
G01X713974Y13643D02*
G02X712854Y14763I0J1120D01*
G01X713974Y12343D02*
G02X711554Y14763I0J2420D01*
G01X715093Y13643D02*
X713974D01*
G01X715092Y12343D02*
X713974D01*
G01X701636Y22077D02*
X697388Y42059D01*
G01X702473Y18402D02*
X700414Y21571D01*
G01X702526Y20709D02*
X701636Y22078D01*
G01X703413Y19342D02*
X702526Y20709D01*
G01X703922Y17461D02*
X702473Y18402D01*
G01X704428Y18683D02*
X703413Y19342D01*
G01X705772Y17068D02*
X703922Y17461D01*
G01X705909Y18368D02*
X704428Y18683D01*
G01X708005Y17068D02*
X705772D01*
G01X708006Y18368D02*
X705909D01*
G01X701636Y22077D02*
X697388Y42059D01*
G01X702526Y20709D02*
X701636Y22078D01*
G01X702473Y18402D02*
X700414Y21571D01*
G01X703413Y19342D02*
X702526Y20709D01*
G01X702473Y18402D02*
X700414Y21571D01*
G01X704428Y18683D02*
X703413Y19342D01*
G01X703922Y17461D02*
X702473Y18402D01*
G01X705909Y18368D02*
X704428Y18683D01*
G01X705772Y17068D02*
X703922Y17461D01*
G01X708006Y18368D02*
X705909D01*
G01X708005Y17068D02*
X705772D01*
G01X712634Y93999D02*
X711478D01*
G01X712635Y95299D02*
X711478D01*
G01X713973Y93443D02*
G03X712634Y93999I-1340J-1337D01*
G01X714892Y94363D02*
G03X712635Y95299I-2259J-2257D01*
G01X714562Y92856D02*
X713973Y93443D01*
G01X715481Y93777D02*
X714892Y94363D01*
G01X716284Y92973D02*
X715481Y93776D01*
G01X715268Y92150D02*
X714562Y92856D01*
G01X715481Y93777D02*
X714892Y94363D01*
G01X716284Y92973D02*
X715481Y93776D01*
G01X720668Y83834D02*
X715268Y92150D01*
G01X721635Y84734D02*
X716284Y92973D01*
G01X728649Y77800D02*
X720668Y83834D01*
G01X729433Y78837D02*
X721635Y84734D01*
G01X729434Y78837D02*
X729433D01*
G01X731082Y75960D02*
X730101Y75824D01*
G01X747813Y64942D02*
X729434Y78837D01*
G01X732398Y74965D02*
X731082Y75960D01*
G01X747813Y64942D02*
X729434Y78837D01*
G01X734831Y73126D02*
X733850Y72990D01*
G01X747813Y64942D02*
X729434Y78837D01*
G01X736147Y72131D02*
X734831Y73126D01*
G01X747813Y64942D02*
X729434Y78837D01*
G01X738579Y70292D02*
X737599Y70156D01*
G01X747813Y64942D02*
X729434Y78837D01*
G01X746846Y64042D02*
X738579Y70292D01*
G01X747813Y64942D02*
X729434Y78837D01*
G01X747966Y62319D02*
X746846Y64042D01*
G01X754829Y54137D02*
X747813Y64942D01*
G01X749084Y60595D02*
X747966Y62319D01*
G01X754829Y54137D02*
X747813Y64942D01*
G01X750227Y58835D02*
X749084Y60595D01*
G01X754829Y54137D02*
X747813Y64942D01*
G01X750773Y57993D02*
X750227Y58835D01*
G01X754829Y54137D02*
X747813Y64942D01*
G01X751917Y56232D02*
X750773Y57993D01*
G01X754829Y54137D02*
X747813Y64942D01*
G01X753607Y53631D02*
X751917Y56232D01*
G01X754829Y54137D02*
X747813Y64942D01*
G01X753840Y52533D02*
X753607Y53631D01*
G01X755374Y51569D02*
X754829Y54137D01*
G01X754074Y51432D02*
X753840Y52533D01*
G01X755374Y51569D02*
X754829Y54137D01*
G01X712635Y95299D02*
X711478D01*
G01X712634Y93999D02*
X711478D01*
G01X714892Y94363D02*
G03X712635Y95299I-2259J-2257D01*
G01X713973Y93443D02*
G03X712634Y93999I-1340J-1337D01*
G01X715481Y93777D02*
X714892Y94363D01*
G01X714562Y92856D02*
X713973Y93443D01*
G01X715268Y92150D02*
X714562Y92856D01*
G01X716284Y92973D02*
X715481Y93776D01*
G01X714562Y92856D02*
X713973Y93443D01*
G01X715268Y92150D02*
X714562Y92856D01*
G01X721635Y84734D02*
X716284Y92973D01*
G01X720668Y83834D02*
X715268Y92150D01*
G01X729433Y78837D02*
X721635Y84734D01*
G01X728649Y77800D02*
X720668Y83834D01*
G01X729434Y78837D02*
X729433D01*
G01X728649Y77800D02*
X720668Y83834D01*
G01X747813Y64942D02*
X729434Y78837D01*
G01X731082Y75960D02*
X730101Y75824D01*
G01X732398Y74965D02*
X731082Y75960D01*
G01X734831Y73126D02*
X733850Y72990D01*
G01X736147Y72131D02*
X734831Y73126D01*
G01X738579Y70292D02*
X737599Y70156D01*
G01X746846Y64042D02*
X738579Y70292D01*
G01X754829Y54137D02*
X747813Y64942D01*
G01X747966Y62319D02*
X746846Y64042D01*
G01X749084Y60595D02*
X747966Y62319D01*
G01X750227Y58835D02*
X749084Y60595D01*
G01X750773Y57993D02*
X750227Y58835D01*
G01X751917Y56232D02*
X750773Y57993D01*
G01X753607Y53631D02*
X751917Y56232D01*
G01X755374Y51569D02*
X754829Y54137D01*
G01X753840Y52533D02*
X753607Y53631D01*
G01X754074Y51432D02*
X753840Y52533D01*
G01X704706Y92110D02*
X703491D01*
G01X704706Y93410D02*
X703491D01*
G01X705956Y90860D02*
G03X704706Y92110I-1250J0D01*
G01X707256Y90860D02*
G03X704706Y93410I-2550J0D01*
G01X705956Y88533D02*
Y90860D01*
G01X707256Y88671D02*
Y90860D01*
G01X706149Y87627D02*
X705956Y88533D01*
G01X707585Y87126D02*
X707256Y88671D01*
G01X706363Y86619D02*
X706149Y87627D01*
G01X707585Y87126D02*
X707256Y88671D01*
G01X708259Y83699D02*
X706363Y86619D01*
G01X709206Y84630D02*
X707585Y87126D01*
G01X721490Y74773D02*
X708259Y83699D01*
G01X740482Y63531D02*
X709206Y84630D01*
G01X724018Y73068D02*
X723046Y72879D01*
G01X740482Y63531D02*
X709206Y84630D01*
G01X725386Y72145D02*
X724018Y73068D01*
G01X740482Y63531D02*
X709206Y84630D01*
G01X727914Y70440D02*
X726942Y70251D01*
G01X740482Y63531D02*
X709206Y84630D01*
G01X729282Y69517D02*
X727914Y70440D01*
G01X740482Y63531D02*
X709206Y84630D01*
G01X731810Y67811D02*
X730838Y67622D01*
G01X740482Y63531D02*
X709206Y84630D01*
G01X739535Y62600D02*
X731810Y67811D01*
G01X740482Y63531D02*
X709206Y84630D01*
G01X745635Y53213D02*
X739535Y62600D01*
G01X746857Y53719D02*
X740482Y63531D01*
G01X704706Y93410D02*
X703491D01*
G01X704706Y92110D02*
X703491D01*
G01X707256Y90860D02*
G03X704706Y93410I-2550J0D01*
G01X705956Y90860D02*
G03X704706Y92110I-1250J0D01*
G01X707256Y88671D02*
Y90860D01*
G01X705956Y88533D02*
Y90860D01*
G01X707585Y87126D02*
X707256Y88671D01*
G01X706149Y87627D02*
X705956Y88533D01*
G01X706363Y86619D02*
X706149Y87627D01*
G01X709206Y84630D02*
X707585Y87126D01*
G01X708259Y83699D02*
X706363Y86619D01*
G01X740482Y63531D02*
X709206Y84630D01*
G01X721490Y74773D02*
X708259Y83699D01*
G01X724018Y73068D02*
X723046Y72879D01*
G01X725386Y72145D02*
X724018Y73068D01*
G01X727914Y70440D02*
X726942Y70251D01*
G01X729282Y69517D02*
X727914Y70440D01*
G01X731810Y67811D02*
X730838Y67622D01*
G01X739535Y62600D02*
X731810Y67811D01*
G01X746857Y53719D02*
X740482Y63531D01*
G01X745635Y53213D02*
X739535Y62600D01*
G01X697774Y85711D02*
Y90974D01*
G01X699074Y85848D02*
Y90974D01*
G01X699076Y79584D02*
X697774Y85711D01*
G01X699823Y82324D02*
X699074Y85848D01*
G01X699870Y82104D02*
X699823Y82324D01*
G01X700298Y80090D02*
X699870Y82104D01*
G01X699925Y78277D02*
X699076Y79584D01*
G01X700583Y79653D02*
X700298Y80091D01*
G01X700865Y79217D02*
X700583Y79653D01*
G01X700789Y77715D02*
X699925Y78277D01*
G01X701065Y79088D02*
X700865Y79218D01*
G01X701157Y79029D02*
X701065Y79088D01*
G01X701613Y78732D02*
X701157Y79029D01*
G01X700790Y77715D02*
X700789D01*
G01X701613Y78732D02*
X701157Y79029D01*
G01X700903Y77641D02*
X700790Y77715D01*
G01X701613Y78732D02*
X701157Y79029D01*
G01X700916Y77633D02*
X700903Y77641D01*
G01X701613Y78732D02*
X701157Y79029D01*
G01X701560Y77214D02*
X700916Y77633D01*
G01X701613Y78732D02*
X701157Y79029D01*
G01X701619Y78728D02*
X701614Y78731D01*
G01X701678Y78690D02*
X701626Y78723D01*
G01X702084Y78432D02*
X701678Y78690D01*
G01X714336Y74498D02*
X701560Y77214D01*
G01X714854Y75718D02*
X702084Y78432D01*
G01X720821Y70124D02*
X714336Y74498D01*
G01X736447Y61154D02*
X714854Y75718D01*
G01X723350Y68419D02*
X722378Y68230D01*
G01X736447Y61154D02*
X714854Y75718D01*
G01X724718Y67496D02*
X723350Y68419D01*
G01X736447Y61154D02*
X714854Y75718D01*
G01X727247Y65791D02*
X726275Y65602D01*
G01X736447Y61154D02*
X714854Y75718D01*
G01X728615Y64868D02*
X727247Y65791D01*
G01X736447Y61154D02*
X714854Y75718D01*
G01X731144Y63162D02*
X730172Y62973D01*
G01X736447Y61154D02*
X714854Y75718D01*
G01X735500Y60224D02*
X731144Y63162D01*
G01X736447Y61154D02*
X714854Y75718D01*
G01X739312Y54349D02*
X735500Y60224D01*
G01X740534Y54855D02*
X736447Y61154D01*
G01X739901Y51579D02*
X739312Y54349D01*
G01X741201Y51716D02*
X740534Y54855D01*
G01X699074Y85848D02*
Y90974D01*
G01X697774Y85711D02*
Y90974D01*
G01X699823Y82324D02*
X699074Y85848D01*
G01X699076Y79584D02*
X697774Y85711D01*
G01X699870Y82104D02*
X699823Y82324D01*
G01X699076Y79584D02*
X697774Y85711D01*
G01X700298Y80090D02*
X699870Y82104D01*
G01X699076Y79584D02*
X697774Y85711D01*
G01X700583Y79653D02*
X700298Y80091D01*
G01X699925Y78277D02*
X699076Y79584D01*
G01X700865Y79217D02*
X700583Y79653D01*
G01X699925Y78277D02*
X699076Y79584D01*
G01X701065Y79088D02*
X700865Y79218D01*
G01X700789Y77715D02*
X699925Y78277D01*
G01X701157Y79029D02*
X701065Y79088D01*
G01X700789Y77715D02*
X699925Y78277D01*
G01X701613Y78732D02*
X701157Y79029D01*
G01X700789Y77715D02*
X699925Y78277D01*
G01X700790Y77715D02*
X700789D01*
G01X700903Y77641D02*
X700790Y77715D01*
G01X700916Y77633D02*
X700903Y77641D01*
G01X701560Y77214D02*
X700916Y77633D01*
G01X701619Y78728D02*
X701614Y78731D01*
G01X701560Y77214D02*
X700916Y77633D01*
G01X701678Y78690D02*
X701626Y78723D01*
G01X701560Y77214D02*
X700916Y77633D01*
G01X702084Y78432D02*
X701678Y78690D01*
G01X701560Y77214D02*
X700916Y77633D01*
G01X714854Y75718D02*
X702084Y78432D01*
G01X714336Y74498D02*
X701560Y77214D01*
G01X736447Y61154D02*
X714854Y75718D01*
G01X720821Y70124D02*
X714336Y74498D01*
G01X723350Y68419D02*
X722378Y68230D01*
G01X724718Y67496D02*
X723350Y68419D01*
G01X727247Y65791D02*
X726275Y65602D01*
G01X728615Y64868D02*
X727247Y65791D01*
G01X731144Y63162D02*
X730172Y62973D01*
G01X735500Y60224D02*
X731144Y63162D01*
G01X740534Y54855D02*
X736447Y61154D01*
G01X739312Y54349D02*
X735500Y60224D01*
G01X741201Y51716D02*
X740534Y54855D01*
G01X739901Y51579D02*
X739312Y54349D01*
G01X701469Y73014D02*
X698296Y75154D01*
G01X701977Y74240D02*
X699127Y76162D01*
G01X710441Y71269D02*
X701469Y73014D01*
G01X710949Y72495D02*
X701977Y74240D01*
G01X714751Y68362D02*
X710441Y71269D01*
G01X727377Y61415D02*
X710949Y72495D01*
G01X717279Y66657D02*
X716307Y66468D01*
G01X727377Y61415D02*
X710949Y72495D01*
G01X718647Y65734D02*
X717279Y66657D01*
G01X727377Y61415D02*
X710949Y72495D01*
G01X721175Y64029D02*
X720203Y63840D01*
G01X727377Y61415D02*
X710949Y72495D01*
G01X722543Y63106D02*
X721175Y64029D01*
G01X727377Y61415D02*
X710949Y72495D01*
G01X725072Y61401D02*
X724100Y61212D01*
G01X727377Y61415D02*
X710949Y72495D01*
G01X726440Y60478D02*
X725072Y61401D01*
G01X727377Y61415D02*
X710949Y72495D01*
G01X729310Y56223D02*
X726440Y60478D01*
G01X730388Y56950D02*
X727377Y61415D01*
G01X731834Y52481D02*
X729310Y56223D01*
G01X731650Y55079D02*
X730388Y56950D01*
G01X733060Y52989D02*
X731650Y55079D01*
G01X701977Y74240D02*
X699127Y76162D01*
G01X701469Y73014D02*
X698296Y75154D01*
G01X710949Y72495D02*
X701977Y74240D01*
G01X710441Y71269D02*
X701469Y73014D01*
G01X727377Y61415D02*
X710949Y72495D01*
G01X714751Y68362D02*
X710441Y71269D01*
G01X717279Y66657D02*
X716307Y66468D01*
G01X718647Y65734D02*
X717279Y66657D01*
G01X721175Y64029D02*
X720203Y63840D01*
G01X722543Y63106D02*
X721175Y64029D01*
G01X725072Y61401D02*
X724100Y61212D01*
G01X726440Y60478D02*
X725072Y61401D01*
G01X730388Y56950D02*
X727377Y61415D01*
G01X729310Y56223D02*
X726440Y60478D01*
G01X731650Y55079D02*
X730388Y56950D01*
G01X731834Y52481D02*
X729310Y56223D01*
G01X733060Y52989D02*
X731650Y55079D01*
G01X731834Y52481D02*
X729310Y56223D01*
G01X700077Y69422D02*
X699103Y69243D01*
G01X701435Y68485D02*
X700077Y69422D01*
G01X709196Y66600D02*
X701435Y68485D01*
G01X709718Y67812D02*
X701975Y69692D01*
G01X723580Y57263D02*
X709196Y66600D01*
G01X724511Y58209D02*
X709718Y67812D01*
G01X724357Y56107D02*
X723580Y57263D01*
G01X726674Y54993D02*
X724511Y58209D01*
G01X725448Y54486D02*
X724357Y56106D01*
G01X726674Y54993D02*
X724511Y58209D01*
G01X725727Y53047D02*
X725448Y54486D01*
G01X726864Y54015D02*
X726674Y54993D01*
G01X727027Y53172D02*
X726864Y54015D01*
G01X700077Y69422D02*
X699103Y69243D01*
G01X701435Y68485D02*
X700077Y69422D01*
G01X709718Y67812D02*
X701975Y69692D01*
G01X709196Y66600D02*
X701435Y68485D01*
G01X724511Y58209D02*
X709718Y67812D01*
G01X723580Y57263D02*
X709196Y66600D01*
G01X726674Y54993D02*
X724511Y58209D01*
G01X724357Y56107D02*
X723580Y57263D01*
G01X725448Y54486D02*
X724357Y56106D01*
G01X726864Y54015D02*
X726674Y54993D01*
G01X725727Y53047D02*
X725448Y54486D01*
G01X727027Y53172D02*
X726864Y54015D01*
G01X725727Y53047D02*
X725448Y54486D01*
G01X702579Y62155D02*
X697734Y65423D01*
G01X709450Y60818D02*
X702579Y62155D01*
G01X709958Y62044D02*
X703087Y63381D01*
G01X712846Y58526D02*
X709450Y60818D01*
G01X714912Y58701D02*
X709958Y62044D01*
G01X713975Y57764D02*
X712846Y58526D01*
G01X714912Y58701D02*
X709958Y62044D01*
G01X717719Y52215D02*
X713975Y57764D01*
G01X718905Y52784D02*
X714912Y58701D01*
G01X702579Y62155D02*
X697734Y65423D01*
G01X709958Y62044D02*
X703087Y63381D01*
G01X709450Y60818D02*
X702579Y62155D01*
G01X714912Y58701D02*
X709958Y62044D01*
G01X712846Y58526D02*
X709450Y60818D01*
G01X713975Y57764D02*
X712846Y58526D01*
G01X718905Y52784D02*
X714912Y58701D01*
G01X717719Y52215D02*
X713975Y57764D01*
G01X708125Y56811D02*
X698337Y58709D01*
G01X708633Y58037D02*
X698845Y59936D01*
G01X710352Y55306D02*
X708125Y56811D01*
G01X711299Y56236D02*
X708633Y58037D01*
G01X711089Y54171D02*
X710352Y55306D01*
G01X712311Y54677D02*
X711299Y56236D01*
G01X711554Y51984D02*
X711089Y54171D01*
G01X712854Y52121D02*
X712311Y54677D01*
G01X708633Y58037D02*
X698845Y59936D01*
G01X708125Y56811D02*
X698337Y58709D01*
G01X711299Y56236D02*
X708633Y58037D01*
G01X710352Y55306D02*
X708125Y56811D01*
G01X712311Y54677D02*
X711299Y56236D01*
G01X711089Y54171D02*
X710352Y55306D01*
G01X712854Y52121D02*
X712311Y54677D01*
G01X711554Y51984D02*
X711089Y54171D01*
M02*
